FILE_TYPE = MACRO_DRAWING;
SET COLOR_WIRE YELLOW;
SET COLOR_PROP MONO;
SET COLOR_DOT WHITE;
SET COLOR_ARC YELLOW;
SET COLOR_BODY GREEN;
SET COLOR_NOTE MONO;
SET PROP_DISPLAY VALUE;
SET PAGE_NUMBER P50;
FORCEADD GND..1
R 2
(5950 750);
FORCEPROP 3 LASTPIN (5950 800) SIG_NAME GND\g
J 0
(5960 810);
DISPLAY 0.659574 (5960 810);
PAINT MONO (5960 810);
DISPLAY INVISIBLE (5960 810);
FORCEPROP 1 LAST VOLTAGE 0
J 0
(5950 750);
PAINT SKYBLUE (5950 750);
DISPLAY INVISIBLE (5950 750);
FORCEPROP 2 LAST BOM_COST MEM
J 0
(5950 755);
PAINT ORANGE (5950 755);
DISPLAY INVISIBLE (5950 755);
FORCEPROP 2 LAST CDS_LIB mstr_symbols
J 0
(5950 750);
DISPLAY 0.787234 (5950 750);
PAINT MONO (5950 750);
DISPLAY INVISIBLE (5950 750);
FORCEPROP 1 LAST SIZE 1B
J 2
(5875 700);
DISPLAY 1.170213 (5875 700);
PAINT GREEN (5875 700);
DISPLAY INVISIBLE (5875 700);
FORCEPROP 1 LAST BODY_TYPE PLUMBING
J 2
(5995 707);
DISPLAY 0.340426 (5995 707);
PAINT GREEN (5995 707);
DISPLAY INVISIBLE (5995 707);
FORCEPROP 1 LAST PATH I1
J 2
(5875 750);
DISPLAY 0.872340 (5875 750);
PAINT AQUA (5875 750);
DISPLAY INVISIBLE (5875 750);
FORCEPROP 2 LAST ROOM DDR4_CH_B
J 0
(5950 755);
PAINT ORANGE (5950 755);
DISPLAY INVISIBLE (5950 755);
FORCEPROP 1 LAST HDL_POWER GND
J 2
(5950 900);
DISPLAY 0.553191 (5950 900);
PAINT GREEN (5950 900);
DISPLAY INVISIBLE (5950 900);
FORCEADD TAP..6
R 2
(4350 4350);
FORCEPROP 3 LASTPIN (4300 4350) SIG_NAME M_D_DQS_DN<13>
J 0
(4310 4360);
DISPLAY 0.659574 (4310 4360);
PAINT MONO (4310 4360);
DISPLAY INVISIBLE (4310 4360);
FORCEPROP 1 LASTPIN (4300 4350) BN 13
J 2
(4350 4360);
DISPLAY 0.617021 (4350 4360);
PAINT PINK (4350 4360);
FORCEPROP 2 LAST CDS_LIB mstr_standard
J 0
(4350 4350);
DISPLAY 0.787234 (4350 4350);
PAINT MONO (4350 4350);
DISPLAY INVISIBLE (4350 4350);
FORCEPROP 1 LAST BODY_TYPE PLUMBING
J 2
(4350 4300);
DISPLAY 1.234043 (4350 4300);
PAINT GREEN (4350 4300);
DISPLAY INVISIBLE (4350 4300);
FORCEPROP 1 LAST HDL_TAP TRUE
J 2
(4025 4225);
DISPLAY 1.234043 (4025 4225);
PAINT GREEN (4025 4225);
DISPLAY INVISIBLE (4025 4225);
FORCEPROP 1 LAST PATH I10
J 2
(4352 4350);
DISPLAY 0.872340 (4352 4350);
PAINT GREEN (4352 4350);
DISPLAY INVISIBLE (4352 4350);
FORCEADD TAP..6
R 2
(1700 3050);
FORCEPROP 3 LASTPIN (1650 3050) SIG_NAME M_D_DQ<29>
J 0
(1660 3060);
DISPLAY 0.659574 (1660 3060);
PAINT MONO (1660 3060);
DISPLAY INVISIBLE (1660 3060);
FORCEPROP 1 LASTPIN (1650 3050) BN 29
J 2
(1700 3060);
DISPLAY 0.617021 (1700 3060);
PAINT PINK (1700 3060);
FORCEPROP 2 LAST CDS_LIB mstr_standard
J 2
(1700 3050);
DISPLAY 0.787234 (1700 3050);
PAINT MONO (1700 3050);
DISPLAY INVISIBLE (1700 3050);
FORCEPROP 1 LAST BODY_TYPE PLUMBING
J 2
(1700 3000);
DISPLAY 1.234043 (1700 3000);
PAINT GREEN (1700 3000);
DISPLAY INVISIBLE (1700 3000);
FORCEPROP 1 LAST HDL_TAP TRUE
J 2
(1375 2925);
DISPLAY 1.234043 (1375 2925);
PAINT GREEN (1375 2925);
DISPLAY INVISIBLE (1375 2925);
FORCEPROP 1 LAST PATH I100
J 2
(1702 3050);
DISPLAY 0.872340 (1702 3050);
PAINT GREEN (1702 3050);
DISPLAY INVISIBLE (1702 3050);
FORCEADD TAP..6
R 2
(1700 2850);
FORCEPROP 3 LASTPIN (1650 2850) SIG_NAME M_D_DQ<25>
J 0
(1660 2860);
DISPLAY 0.659574 (1660 2860);
PAINT MONO (1660 2860);
DISPLAY INVISIBLE (1660 2860);
FORCEPROP 1 LASTPIN (1650 2850) BN 25
J 2
(1700 2860);
DISPLAY 0.617021 (1700 2860);
PAINT PINK (1700 2860);
FORCEPROP 2 LAST CDS_LIB mstr_standard
J 2
(1700 2850);
DISPLAY 0.787234 (1700 2850);
PAINT MONO (1700 2850);
DISPLAY INVISIBLE (1700 2850);
FORCEPROP 1 LAST BODY_TYPE PLUMBING
J 2
(1700 2800);
DISPLAY 1.234043 (1700 2800);
PAINT GREEN (1700 2800);
DISPLAY INVISIBLE (1700 2800);
FORCEPROP 1 LAST HDL_TAP TRUE
J 2
(1375 2725);
DISPLAY 1.234043 (1375 2725);
PAINT GREEN (1375 2725);
DISPLAY INVISIBLE (1375 2725);
FORCEPROP 1 LAST PATH I101
J 2
(1702 2850);
DISPLAY 0.872340 (1702 2850);
PAINT GREEN (1702 2850);
DISPLAY INVISIBLE (1702 2850);
FORCEADD TAP..6
R 2
(1700 2800);
FORCEPROP 3 LASTPIN (1650 2800) SIG_NAME M_D_DQ<24>
J 0
(1660 2810);
DISPLAY 0.659574 (1660 2810);
PAINT MONO (1660 2810);
DISPLAY INVISIBLE (1660 2810);
FORCEPROP 1 LASTPIN (1650 2800) BN 24
J 2
(1700 2810);
DISPLAY 0.617021 (1700 2810);
PAINT PINK (1700 2810);
FORCEPROP 2 LAST CDS_LIB mstr_standard
J 2
(1700 2800);
DISPLAY 0.787234 (1700 2800);
PAINT MONO (1700 2800);
DISPLAY INVISIBLE (1700 2800);
FORCEPROP 1 LAST BODY_TYPE PLUMBING
J 2
(1700 2750);
DISPLAY 1.234043 (1700 2750);
PAINT GREEN (1700 2750);
DISPLAY INVISIBLE (1700 2750);
FORCEPROP 1 LAST HDL_TAP TRUE
J 2
(1375 2675);
DISPLAY 1.234043 (1375 2675);
PAINT GREEN (1375 2675);
DISPLAY INVISIBLE (1375 2675);
FORCEPROP 1 LAST PATH I102
J 2
(1702 2800);
DISPLAY 0.872340 (1702 2800);
PAINT GREEN (1702 2800);
DISPLAY INVISIBLE (1702 2800);
FORCEADD TAP..6
R 2
(1700 2900);
FORCEPROP 3 LASTPIN (1650 2900) SIG_NAME M_D_DQ<26>
J 0
(1660 2910);
DISPLAY 0.659574 (1660 2910);
PAINT MONO (1660 2910);
DISPLAY INVISIBLE (1660 2910);
FORCEPROP 1 LASTPIN (1650 2900) BN 26
J 2
(1700 2910);
DISPLAY 0.617021 (1700 2910);
PAINT PINK (1700 2910);
FORCEPROP 2 LAST CDS_LIB mstr_standard
J 2
(1700 2900);
DISPLAY 0.787234 (1700 2900);
PAINT MONO (1700 2900);
DISPLAY INVISIBLE (1700 2900);
FORCEPROP 1 LAST BODY_TYPE PLUMBING
J 2
(1700 2850);
DISPLAY 1.234043 (1700 2850);
PAINT GREEN (1700 2850);
DISPLAY INVISIBLE (1700 2850);
FORCEPROP 1 LAST HDL_TAP TRUE
J 2
(1375 2775);
DISPLAY 1.234043 (1375 2775);
PAINT GREEN (1375 2775);
DISPLAY INVISIBLE (1375 2775);
FORCEPROP 1 LAST PATH I103
J 2
(1702 2900);
DISPLAY 0.872340 (1702 2900);
PAINT GREEN (1702 2900);
DISPLAY INVISIBLE (1702 2900);
FORCEADD TAP..6
R 2
(1700 2950);
FORCEPROP 3 LASTPIN (1650 2950) SIG_NAME M_D_DQ<27>
J 0
(1660 2960);
DISPLAY 0.659574 (1660 2960);
PAINT MONO (1660 2960);
DISPLAY INVISIBLE (1660 2960);
FORCEPROP 1 LASTPIN (1650 2950) BN 27
J 2
(1700 2960);
DISPLAY 0.617021 (1700 2960);
PAINT PINK (1700 2960);
FORCEPROP 2 LAST CDS_LIB mstr_standard
J 2
(1700 2950);
DISPLAY 0.787234 (1700 2950);
PAINT MONO (1700 2950);
DISPLAY INVISIBLE (1700 2950);
FORCEPROP 1 LAST BODY_TYPE PLUMBING
J 2
(1700 2900);
DISPLAY 1.234043 (1700 2900);
PAINT GREEN (1700 2900);
DISPLAY INVISIBLE (1700 2900);
FORCEPROP 1 LAST HDL_TAP TRUE
J 2
(1375 2825);
DISPLAY 1.234043 (1375 2825);
PAINT GREEN (1375 2825);
DISPLAY INVISIBLE (1375 2825);
FORCEPROP 1 LAST PATH I104
J 2
(1702 2950);
DISPLAY 0.872340 (1702 2950);
PAINT GREEN (1702 2950);
DISPLAY INVISIBLE (1702 2950);
FORCEADD TAP..6
R 2
(1700 3000);
FORCEPROP 3 LASTPIN (1650 3000) SIG_NAME M_D_DQ<28>
J 0
(1660 3010);
DISPLAY 0.659574 (1660 3010);
PAINT MONO (1660 3010);
DISPLAY INVISIBLE (1660 3010);
FORCEPROP 1 LASTPIN (1650 3000) BN 28
J 2
(1700 3010);
DISPLAY 0.617021 (1700 3010);
PAINT PINK (1700 3010);
FORCEPROP 2 LAST CDS_LIB mstr_standard
J 2
(1700 3000);
DISPLAY 0.787234 (1700 3000);
PAINT MONO (1700 3000);
DISPLAY INVISIBLE (1700 3000);
FORCEPROP 1 LAST BODY_TYPE PLUMBING
J 2
(1700 2950);
DISPLAY 1.234043 (1700 2950);
PAINT GREEN (1700 2950);
DISPLAY INVISIBLE (1700 2950);
FORCEPROP 1 LAST HDL_TAP TRUE
J 2
(1375 2875);
DISPLAY 1.234043 (1375 2875);
PAINT GREEN (1375 2875);
DISPLAY INVISIBLE (1375 2875);
FORCEPROP 1 LAST PATH I105
J 2
(1702 3000);
DISPLAY 0.872340 (1702 3000);
PAINT GREEN (1702 3000);
DISPLAY INVISIBLE (1702 3000);
FORCEADD TAP..6
R 2
(1700 2650);
FORCEPROP 3 LASTPIN (1650 2650) SIG_NAME M_D_DQ<21>
J 0
(1660 2660);
DISPLAY 0.659574 (1660 2660);
PAINT MONO (1660 2660);
DISPLAY INVISIBLE (1660 2660);
FORCEPROP 1 LASTPIN (1650 2650) BN 21
J 2
(1700 2660);
DISPLAY 0.617021 (1700 2660);
PAINT PINK (1700 2660);
FORCEPROP 2 LAST CDS_LIB mstr_standard
J 2
(1700 2650);
DISPLAY 0.787234 (1700 2650);
PAINT MONO (1700 2650);
DISPLAY INVISIBLE (1700 2650);
FORCEPROP 1 LAST BODY_TYPE PLUMBING
J 2
(1700 2600);
DISPLAY 1.234043 (1700 2600);
PAINT GREEN (1700 2600);
DISPLAY INVISIBLE (1700 2600);
FORCEPROP 1 LAST HDL_TAP TRUE
J 2
(1375 2525);
DISPLAY 1.234043 (1375 2525);
PAINT GREEN (1375 2525);
DISPLAY INVISIBLE (1375 2525);
FORCEPROP 1 LAST PATH I106
J 2
(1702 2650);
DISPLAY 0.872340 (1702 2650);
PAINT GREEN (1702 2650);
DISPLAY INVISIBLE (1702 2650);
FORCEADD TAP..6
R 2
(1700 2600);
FORCEPROP 3 LASTPIN (1650 2600) SIG_NAME M_D_DQ<20>
J 0
(1660 2610);
DISPLAY 0.659574 (1660 2610);
PAINT MONO (1660 2610);
DISPLAY INVISIBLE (1660 2610);
FORCEPROP 1 LASTPIN (1650 2600) BN 20
J 2
(1700 2610);
DISPLAY 0.617021 (1700 2610);
PAINT PINK (1700 2610);
FORCEPROP 2 LAST CDS_LIB mstr_standard
J 2
(1700 2600);
DISPLAY 0.787234 (1700 2600);
PAINT MONO (1700 2600);
DISPLAY INVISIBLE (1700 2600);
FORCEPROP 1 LAST BODY_TYPE PLUMBING
J 2
(1700 2550);
DISPLAY 1.234043 (1700 2550);
PAINT GREEN (1700 2550);
DISPLAY INVISIBLE (1700 2550);
FORCEPROP 1 LAST HDL_TAP TRUE
J 2
(1375 2475);
DISPLAY 1.234043 (1375 2475);
PAINT GREEN (1375 2475);
DISPLAY INVISIBLE (1375 2475);
FORCEPROP 1 LAST PATH I107
J 2
(1702 2600);
DISPLAY 0.872340 (1702 2600);
PAINT GREEN (1702 2600);
DISPLAY INVISIBLE (1702 2600);
FORCEADD TAP..6
R 2
(1700 2550);
FORCEPROP 3 LASTPIN (1650 2550) SIG_NAME M_D_DQ<19>
J 0
(1660 2560);
DISPLAY 0.659574 (1660 2560);
PAINT MONO (1660 2560);
DISPLAY INVISIBLE (1660 2560);
FORCEPROP 1 LASTPIN (1650 2550) BN 19
J 2
(1700 2560);
DISPLAY 0.617021 (1700 2560);
PAINT PINK (1700 2560);
FORCEPROP 2 LAST CDS_LIB mstr_standard
J 2
(1700 2550);
DISPLAY 0.787234 (1700 2550);
PAINT MONO (1700 2550);
DISPLAY INVISIBLE (1700 2550);
FORCEPROP 1 LAST BODY_TYPE PLUMBING
J 2
(1700 2500);
DISPLAY 1.234043 (1700 2500);
PAINT GREEN (1700 2500);
DISPLAY INVISIBLE (1700 2500);
FORCEPROP 1 LAST HDL_TAP TRUE
J 2
(1375 2425);
DISPLAY 1.234043 (1375 2425);
PAINT GREEN (1375 2425);
DISPLAY INVISIBLE (1375 2425);
FORCEPROP 1 LAST PATH I108
J 2
(1702 2550);
DISPLAY 0.872340 (1702 2550);
PAINT GREEN (1702 2550);
DISPLAY INVISIBLE (1702 2550);
FORCEADD TAP..6
R 2
(1700 2700);
FORCEPROP 3 LASTPIN (1650 2700) SIG_NAME M_D_DQ<22>
J 0
(1660 2710);
DISPLAY 0.659574 (1660 2710);
PAINT MONO (1660 2710);
DISPLAY INVISIBLE (1660 2710);
FORCEPROP 1 LASTPIN (1650 2700) BN 22
J 2
(1700 2710);
DISPLAY 0.617021 (1700 2710);
PAINT PINK (1700 2710);
FORCEPROP 2 LAST CDS_LIB mstr_standard
J 2
(1700 2700);
DISPLAY 0.787234 (1700 2700);
PAINT MONO (1700 2700);
DISPLAY INVISIBLE (1700 2700);
FORCEPROP 1 LAST BODY_TYPE PLUMBING
J 2
(1700 2650);
DISPLAY 1.234043 (1700 2650);
PAINT GREEN (1700 2650);
DISPLAY INVISIBLE (1700 2650);
FORCEPROP 1 LAST HDL_TAP TRUE
J 2
(1375 2575);
DISPLAY 1.234043 (1375 2575);
PAINT GREEN (1375 2575);
DISPLAY INVISIBLE (1375 2575);
FORCEPROP 1 LAST PATH I109
J 2
(1702 2700);
DISPLAY 0.872340 (1702 2700);
PAINT GREEN (1702 2700);
DISPLAY INVISIBLE (1702 2700);
FORCEADD TAP..6
R 2
(4350 4450);
FORCEPROP 3 LASTPIN (4300 4450) SIG_NAME M_D_DQS_DN<14>
J 0
(4310 4460);
DISPLAY 0.659574 (4310 4460);
PAINT MONO (4310 4460);
DISPLAY INVISIBLE (4310 4460);
FORCEPROP 1 LASTPIN (4300 4450) BN 14
J 2
(4350 4460);
DISPLAY 0.617021 (4350 4460);
PAINT PINK (4350 4460);
FORCEPROP 2 LAST CDS_LIB mstr_standard
J 0
(4350 4450);
DISPLAY 0.787234 (4350 4450);
PAINT MONO (4350 4450);
DISPLAY INVISIBLE (4350 4450);
FORCEPROP 1 LAST BODY_TYPE PLUMBING
J 2
(4350 4400);
DISPLAY 1.234043 (4350 4400);
PAINT GREEN (4350 4400);
DISPLAY INVISIBLE (4350 4400);
FORCEPROP 1 LAST HDL_TAP TRUE
J 2
(4025 4325);
DISPLAY 1.234043 (4025 4325);
PAINT GREEN (4025 4325);
DISPLAY INVISIBLE (4025 4325);
FORCEPROP 1 LAST PATH I11
J 2
(4352 4450);
DISPLAY 0.872340 (4352 4450);
PAINT GREEN (4352 4450);
DISPLAY INVISIBLE (4352 4450);
FORCEADD TAP..6
R 2
(1700 2750);
FORCEPROP 3 LASTPIN (1650 2750) SIG_NAME M_D_DQ<23>
J 0
(1660 2760);
DISPLAY 0.659574 (1660 2760);
PAINT MONO (1660 2760);
DISPLAY INVISIBLE (1660 2760);
FORCEPROP 1 LASTPIN (1650 2750) BN 23
J 2
(1700 2760);
DISPLAY 0.617021 (1700 2760);
PAINT PINK (1700 2760);
FORCEPROP 2 LAST CDS_LIB mstr_standard
J 2
(1700 2750);
DISPLAY 0.787234 (1700 2750);
PAINT MONO (1700 2750);
DISPLAY INVISIBLE (1700 2750);
FORCEPROP 1 LAST BODY_TYPE PLUMBING
J 2
(1700 2700);
DISPLAY 1.234043 (1700 2700);
PAINT GREEN (1700 2700);
DISPLAY INVISIBLE (1700 2700);
FORCEPROP 1 LAST HDL_TAP TRUE
J 2
(1375 2625);
DISPLAY 1.234043 (1375 2625);
PAINT GREEN (1375 2625);
DISPLAY INVISIBLE (1375 2625);
FORCEPROP 1 LAST PATH I110
J 2
(1702 2750);
DISPLAY 0.872340 (1702 2750);
PAINT GREEN (1702 2750);
DISPLAY INVISIBLE (1702 2750);
FORCEADD TAP..6
R 2
(1700 2300);
FORCEPROP 3 LASTPIN (1650 2300) SIG_NAME M_D_DQ<14>
J 0
(1660 2310);
DISPLAY 0.659574 (1660 2310);
PAINT MONO (1660 2310);
DISPLAY INVISIBLE (1660 2310);
FORCEPROP 1 LASTPIN (1650 2300) BN 14
J 2
(1700 2310);
DISPLAY 0.617021 (1700 2310);
PAINT PINK (1700 2310);
FORCEPROP 2 LAST CDS_LIB mstr_standard
J 2
(1700 2300);
DISPLAY 0.787234 (1700 2300);
PAINT MONO (1700 2300);
DISPLAY INVISIBLE (1700 2300);
FORCEPROP 1 LAST BODY_TYPE PLUMBING
J 2
(1700 2250);
DISPLAY 1.234043 (1700 2250);
PAINT GREEN (1700 2250);
DISPLAY INVISIBLE (1700 2250);
FORCEPROP 1 LAST HDL_TAP TRUE
J 2
(1375 2175);
DISPLAY 1.234043 (1375 2175);
PAINT GREEN (1375 2175);
DISPLAY INVISIBLE (1375 2175);
FORCEPROP 1 LAST PATH I111
J 2
(1702 2300);
DISPLAY 0.872340 (1702 2300);
PAINT GREEN (1702 2300);
DISPLAY INVISIBLE (1702 2300);
FORCEADD TAP..6
R 2
(1700 2350);
FORCEPROP 3 LASTPIN (1650 2350) SIG_NAME M_D_DQ<15>
J 0
(1660 2360);
DISPLAY 0.659574 (1660 2360);
PAINT MONO (1660 2360);
DISPLAY INVISIBLE (1660 2360);
FORCEPROP 1 LASTPIN (1650 2350) BN 15
J 2
(1700 2360);
DISPLAY 0.617021 (1700 2360);
PAINT PINK (1700 2360);
FORCEPROP 2 LAST CDS_LIB mstr_standard
J 2
(1700 2350);
DISPLAY 0.787234 (1700 2350);
PAINT MONO (1700 2350);
DISPLAY INVISIBLE (1700 2350);
FORCEPROP 1 LAST BODY_TYPE PLUMBING
J 2
(1700 2300);
DISPLAY 1.234043 (1700 2300);
PAINT GREEN (1700 2300);
DISPLAY INVISIBLE (1700 2300);
FORCEPROP 1 LAST HDL_TAP TRUE
J 2
(1375 2225);
DISPLAY 1.234043 (1375 2225);
PAINT GREEN (1375 2225);
DISPLAY INVISIBLE (1375 2225);
FORCEPROP 1 LAST PATH I112
J 2
(1702 2350);
DISPLAY 0.872340 (1702 2350);
PAINT GREEN (1702 2350);
DISPLAY INVISIBLE (1702 2350);
FORCEADD TAP..6
R 2
(1700 2400);
FORCEPROP 3 LASTPIN (1650 2400) SIG_NAME M_D_DQ<16>
J 0
(1660 2410);
DISPLAY 0.659574 (1660 2410);
PAINT MONO (1660 2410);
DISPLAY INVISIBLE (1660 2410);
FORCEPROP 1 LASTPIN (1650 2400) BN 16
J 2
(1700 2410);
DISPLAY 0.617021 (1700 2410);
PAINT PINK (1700 2410);
FORCEPROP 2 LAST CDS_LIB mstr_standard
J 2
(1700 2400);
DISPLAY 0.787234 (1700 2400);
PAINT MONO (1700 2400);
DISPLAY INVISIBLE (1700 2400);
FORCEPROP 1 LAST BODY_TYPE PLUMBING
J 2
(1700 2350);
DISPLAY 1.234043 (1700 2350);
PAINT GREEN (1700 2350);
DISPLAY INVISIBLE (1700 2350);
FORCEPROP 1 LAST HDL_TAP TRUE
J 2
(1375 2275);
DISPLAY 1.234043 (1375 2275);
PAINT GREEN (1375 2275);
DISPLAY INVISIBLE (1375 2275);
FORCEPROP 1 LAST PATH I113
J 2
(1702 2400);
DISPLAY 0.872340 (1702 2400);
PAINT GREEN (1702 2400);
DISPLAY INVISIBLE (1702 2400);
FORCEADD TAP..6
R 2
(1700 2500);
FORCEPROP 3 LASTPIN (1650 2500) SIG_NAME M_D_DQ<18>
J 0
(1660 2510);
DISPLAY 0.659574 (1660 2510);
PAINT MONO (1660 2510);
DISPLAY INVISIBLE (1660 2510);
FORCEPROP 1 LASTPIN (1650 2500) BN 18
J 2
(1700 2510);
DISPLAY 0.617021 (1700 2510);
PAINT PINK (1700 2510);
FORCEPROP 2 LAST CDS_LIB mstr_standard
J 2
(1700 2500);
DISPLAY 0.787234 (1700 2500);
PAINT MONO (1700 2500);
DISPLAY INVISIBLE (1700 2500);
FORCEPROP 1 LAST BODY_TYPE PLUMBING
J 2
(1700 2450);
DISPLAY 1.234043 (1700 2450);
PAINT GREEN (1700 2450);
DISPLAY INVISIBLE (1700 2450);
FORCEPROP 1 LAST HDL_TAP TRUE
J 2
(1375 2375);
DISPLAY 1.234043 (1375 2375);
PAINT GREEN (1375 2375);
DISPLAY INVISIBLE (1375 2375);
FORCEPROP 1 LAST PATH I114
J 2
(1702 2500);
DISPLAY 0.872340 (1702 2500);
PAINT GREEN (1702 2500);
DISPLAY INVISIBLE (1702 2500);
FORCEADD TAP..6
R 2
(1700 2450);
FORCEPROP 3 LASTPIN (1650 2450) SIG_NAME M_D_DQ<17>
J 0
(1660 2460);
DISPLAY 0.659574 (1660 2460);
PAINT MONO (1660 2460);
DISPLAY INVISIBLE (1660 2460);
FORCEPROP 1 LASTPIN (1650 2450) BN 17
J 2
(1700 2460);
DISPLAY 0.617021 (1700 2460);
PAINT PINK (1700 2460);
FORCEPROP 2 LAST CDS_LIB mstr_standard
J 2
(1700 2450);
DISPLAY 0.787234 (1700 2450);
PAINT MONO (1700 2450);
DISPLAY INVISIBLE (1700 2450);
FORCEPROP 1 LAST BODY_TYPE PLUMBING
J 2
(1700 2400);
DISPLAY 1.234043 (1700 2400);
PAINT GREEN (1700 2400);
DISPLAY INVISIBLE (1700 2400);
FORCEPROP 1 LAST HDL_TAP TRUE
J 2
(1375 2325);
DISPLAY 1.234043 (1375 2325);
PAINT GREEN (1375 2325);
DISPLAY INVISIBLE (1375 2325);
FORCEPROP 1 LAST PATH I115
J 2
(1702 2450);
DISPLAY 0.872340 (1702 2450);
PAINT GREEN (1702 2450);
DISPLAY INVISIBLE (1702 2450);
FORCEADD TAP..6
R 2
(1700 2100);
FORCEPROP 3 LASTPIN (1650 2100) SIG_NAME M_D_DQ<10>
J 0
(1660 2110);
DISPLAY 0.659574 (1660 2110);
PAINT MONO (1660 2110);
DISPLAY INVISIBLE (1660 2110);
FORCEPROP 1 LASTPIN (1650 2100) BN 10
J 2
(1700 2110);
DISPLAY 0.617021 (1700 2110);
PAINT PINK (1700 2110);
FORCEPROP 2 LAST CDS_LIB mstr_standard
J 2
(1700 2100);
DISPLAY 0.787234 (1700 2100);
PAINT MONO (1700 2100);
DISPLAY INVISIBLE (1700 2100);
FORCEPROP 1 LAST BODY_TYPE PLUMBING
J 2
(1700 2050);
DISPLAY 1.234043 (1700 2050);
PAINT GREEN (1700 2050);
DISPLAY INVISIBLE (1700 2050);
FORCEPROP 1 LAST HDL_TAP TRUE
J 2
(1375 1975);
DISPLAY 1.234043 (1375 1975);
PAINT GREEN (1375 1975);
DISPLAY INVISIBLE (1375 1975);
FORCEPROP 1 LAST PATH I116
J 2
(1702 2100);
DISPLAY 0.872340 (1702 2100);
PAINT GREEN (1702 2100);
DISPLAY INVISIBLE (1702 2100);
FORCEADD TAP..6
R 2
(1700 2050);
FORCEPROP 3 LASTPIN (1650 2050) SIG_NAME M_D_DQ<9>
J 0
(1660 2060);
DISPLAY 0.659574 (1660 2060);
PAINT MONO (1660 2060);
DISPLAY INVISIBLE (1660 2060);
FORCEPROP 1 LASTPIN (1650 2050) BN 9
J 2
(1700 2060);
DISPLAY 0.617021 (1700 2060);
PAINT PINK (1700 2060);
FORCEPROP 2 LAST CDS_LIB mstr_standard
J 2
(1700 2050);
DISPLAY 0.787234 (1700 2050);
PAINT MONO (1700 2050);
DISPLAY INVISIBLE (1700 2050);
FORCEPROP 1 LAST BODY_TYPE PLUMBING
J 2
(1700 2000);
DISPLAY 1.234043 (1700 2000);
PAINT GREEN (1700 2000);
DISPLAY INVISIBLE (1700 2000);
FORCEPROP 1 LAST HDL_TAP TRUE
J 2
(1375 1925);
DISPLAY 1.234043 (1375 1925);
PAINT GREEN (1375 1925);
DISPLAY INVISIBLE (1375 1925);
FORCEPROP 1 LAST PATH I117
J 2
(1702 2050);
DISPLAY 0.872340 (1702 2050);
PAINT GREEN (1702 2050);
DISPLAY INVISIBLE (1702 2050);
FORCEADD TAP..6
R 2
(1700 2150);
FORCEPROP 3 LASTPIN (1650 2150) SIG_NAME M_D_DQ<11>
J 0
(1660 2160);
DISPLAY 0.659574 (1660 2160);
PAINT MONO (1660 2160);
DISPLAY INVISIBLE (1660 2160);
FORCEPROP 1 LASTPIN (1650 2150) BN 11
J 2
(1700 2160);
DISPLAY 0.617021 (1700 2160);
PAINT PINK (1700 2160);
FORCEPROP 2 LAST CDS_LIB mstr_standard
J 2
(1700 2150);
DISPLAY 0.787234 (1700 2150);
PAINT MONO (1700 2150);
DISPLAY INVISIBLE (1700 2150);
FORCEPROP 1 LAST BODY_TYPE PLUMBING
J 2
(1700 2100);
DISPLAY 1.234043 (1700 2100);
PAINT GREEN (1700 2100);
DISPLAY INVISIBLE (1700 2100);
FORCEPROP 1 LAST HDL_TAP TRUE
J 2
(1375 2025);
DISPLAY 1.234043 (1375 2025);
PAINT GREEN (1375 2025);
DISPLAY INVISIBLE (1375 2025);
FORCEPROP 1 LAST PATH I118
J 2
(1702 2150);
DISPLAY 0.872340 (1702 2150);
PAINT GREEN (1702 2150);
DISPLAY INVISIBLE (1702 2150);
FORCEADD TAP..6
R 2
(1700 2200);
FORCEPROP 3 LASTPIN (1650 2200) SIG_NAME M_D_DQ<12>
J 0
(1660 2210);
DISPLAY 0.659574 (1660 2210);
PAINT MONO (1660 2210);
DISPLAY INVISIBLE (1660 2210);
FORCEPROP 1 LASTPIN (1650 2200) BN 12
J 2
(1700 2210);
DISPLAY 0.617021 (1700 2210);
PAINT PINK (1700 2210);
FORCEPROP 2 LAST CDS_LIB mstr_standard
J 2
(1700 2200);
DISPLAY 0.787234 (1700 2200);
PAINT MONO (1700 2200);
DISPLAY INVISIBLE (1700 2200);
FORCEPROP 1 LAST BODY_TYPE PLUMBING
J 2
(1700 2150);
DISPLAY 1.234043 (1700 2150);
PAINT GREEN (1700 2150);
DISPLAY INVISIBLE (1700 2150);
FORCEPROP 1 LAST HDL_TAP TRUE
J 2
(1375 2075);
DISPLAY 1.234043 (1375 2075);
PAINT GREEN (1375 2075);
DISPLAY INVISIBLE (1375 2075);
FORCEPROP 1 LAST PATH I119
J 2
(1702 2200);
DISPLAY 0.872340 (1702 2200);
PAINT GREEN (1702 2200);
DISPLAY INVISIBLE (1702 2200);
FORCEADD TAP..6
R 2
(4350 4250);
FORCEPROP 3 LASTPIN (4300 4250) SIG_NAME M_D_DQS_DN<12>
J 0
(4310 4260);
DISPLAY 0.659574 (4310 4260);
PAINT MONO (4310 4260);
DISPLAY INVISIBLE (4310 4260);
FORCEPROP 1 LASTPIN (4300 4250) BN 12
J 2
(4350 4260);
DISPLAY 0.617021 (4350 4260);
PAINT PINK (4350 4260);
FORCEPROP 2 LAST CDS_LIB mstr_standard
J 0
(4350 4250);
DISPLAY 0.787234 (4350 4250);
PAINT MONO (4350 4250);
DISPLAY INVISIBLE (4350 4250);
FORCEPROP 1 LAST BODY_TYPE PLUMBING
J 2
(4350 4200);
DISPLAY 1.234043 (4350 4200);
PAINT GREEN (4350 4200);
DISPLAY INVISIBLE (4350 4200);
FORCEPROP 1 LAST HDL_TAP TRUE
J 2
(4025 4125);
DISPLAY 1.234043 (4025 4125);
PAINT GREEN (4025 4125);
DISPLAY INVISIBLE (4025 4125);
FORCEPROP 1 LAST PATH I12
J 2
(4352 4250);
DISPLAY 0.872340 (4352 4250);
PAINT GREEN (4352 4250);
DISPLAY INVISIBLE (4352 4250);
FORCEADD TAP..6
R 2
(1700 2250);
FORCEPROP 3 LASTPIN (1650 2250) SIG_NAME M_D_DQ<13>
J 0
(1660 2260);
DISPLAY 0.659574 (1660 2260);
PAINT MONO (1660 2260);
DISPLAY INVISIBLE (1660 2260);
FORCEPROP 1 LASTPIN (1650 2250) BN 13
J 2
(1700 2260);
DISPLAY 0.617021 (1700 2260);
PAINT PINK (1700 2260);
FORCEPROP 2 LAST CDS_LIB mstr_standard
J 2
(1700 2250);
DISPLAY 0.787234 (1700 2250);
PAINT MONO (1700 2250);
DISPLAY INVISIBLE (1700 2250);
FORCEPROP 1 LAST BODY_TYPE PLUMBING
J 2
(1700 2200);
DISPLAY 1.234043 (1700 2200);
PAINT GREEN (1700 2200);
DISPLAY INVISIBLE (1700 2200);
FORCEPROP 1 LAST HDL_TAP TRUE
J 2
(1375 2125);
DISPLAY 1.234043 (1375 2125);
PAINT GREEN (1375 2125);
DISPLAY INVISIBLE (1375 2125);
FORCEPROP 1 LAST PATH I120
J 2
(1702 2250);
DISPLAY 0.872340 (1702 2250);
PAINT GREEN (1702 2250);
DISPLAY INVISIBLE (1702 2250);
FORCEADD TAP..6
(200 4050);
FORCEPROP 3 LASTPIN (250 4050) SIG_NAME M_D_MA<3>
J 0
(260 4060);
DISPLAY 0.659574 (260 4060);
PAINT MONO (260 4060);
DISPLAY INVISIBLE (260 4060);
FORCEPROP 1 LASTPIN (250 4050) BN 3
J 0
(200 4060);
DISPLAY 0.617021 (200 4060);
PAINT PINK (200 4060);
FORCEPROP 2 LAST CDS_LIB mstr_standard
J 2
(200 4050);
DISPLAY 0.787234 (200 4050);
PAINT MONO (200 4050);
DISPLAY INVISIBLE (200 4050);
FORCEPROP 1 LAST BODY_TYPE PLUMBING
J 0
(200 4000);
DISPLAY 1.234043 (200 4000);
PAINT GREEN (200 4000);
DISPLAY INVISIBLE (200 4000);
FORCEPROP 1 LAST HDL_TAP TRUE
J 0
(525 3925);
DISPLAY 1.234043 (525 3925);
PAINT GREEN (525 3925);
DISPLAY INVISIBLE (525 3925);
FORCEPROP 1 LAST PATH I121
J 0
(198 4050);
DISPLAY 0.872340 (198 4050);
PAINT GREEN (198 4050);
DISPLAY INVISIBLE (198 4050);
FORCEADD TAP..6
(200 3900);
FORCEPROP 3 LASTPIN (250 3900) SIG_NAME M_D_MA<0>
J 0
(260 3910);
DISPLAY 0.659574 (260 3910);
PAINT MONO (260 3910);
DISPLAY INVISIBLE (260 3910);
FORCEPROP 1 LASTPIN (250 3900) BN 0
J 0
(200 3910);
DISPLAY 0.617021 (200 3910);
PAINT PINK (200 3910);
FORCEPROP 2 LAST CDS_LIB mstr_standard
J 2
(200 3900);
DISPLAY 0.787234 (200 3900);
PAINT MONO (200 3900);
DISPLAY INVISIBLE (200 3900);
FORCEPROP 1 LAST BODY_TYPE PLUMBING
J 0
(200 3850);
DISPLAY 1.234043 (200 3850);
PAINT GREEN (200 3850);
DISPLAY INVISIBLE (200 3850);
FORCEPROP 1 LAST HDL_TAP TRUE
J 0
(525 3775);
DISPLAY 1.234043 (525 3775);
PAINT GREEN (525 3775);
DISPLAY INVISIBLE (525 3775);
FORCEPROP 1 LAST PATH I122
J 0
(198 3900);
DISPLAY 0.872340 (198 3900);
PAINT GREEN (198 3900);
DISPLAY INVISIBLE (198 3900);
FORCEADD TAP..6
(200 3950);
FORCEPROP 3 LASTPIN (250 3950) SIG_NAME M_D_MA<1>
J 0
(260 3960);
DISPLAY 0.659574 (260 3960);
PAINT MONO (260 3960);
DISPLAY INVISIBLE (260 3960);
FORCEPROP 1 LASTPIN (250 3950) BN 1
J 0
(200 3960);
DISPLAY 0.617021 (200 3960);
PAINT PINK (200 3960);
FORCEPROP 2 LAST CDS_LIB mstr_standard
J 2
(200 3950);
DISPLAY 0.787234 (200 3950);
PAINT MONO (200 3950);
DISPLAY INVISIBLE (200 3950);
FORCEPROP 1 LAST BODY_TYPE PLUMBING
J 0
(200 3900);
DISPLAY 1.234043 (200 3900);
PAINT GREEN (200 3900);
DISPLAY INVISIBLE (200 3900);
FORCEPROP 1 LAST HDL_TAP TRUE
J 0
(525 3825);
DISPLAY 1.234043 (525 3825);
PAINT GREEN (525 3825);
DISPLAY INVISIBLE (525 3825);
FORCEPROP 1 LAST PATH I123
J 0
(198 3950);
DISPLAY 0.872340 (198 3950);
PAINT GREEN (198 3950);
DISPLAY INVISIBLE (198 3950);
FORCEADD TAP..6
(200 4000);
FORCEPROP 3 LASTPIN (250 4000) SIG_NAME M_D_MA<2>
J 0
(260 4010);
DISPLAY 0.659574 (260 4010);
PAINT MONO (260 4010);
DISPLAY INVISIBLE (260 4010);
FORCEPROP 1 LASTPIN (250 4000) BN 2
J 0
(200 4010);
DISPLAY 0.617021 (200 4010);
PAINT PINK (200 4010);
FORCEPROP 2 LAST CDS_LIB mstr_standard
J 2
(200 4000);
DISPLAY 0.787234 (200 4000);
PAINT MONO (200 4000);
DISPLAY INVISIBLE (200 4000);
FORCEPROP 1 LAST BODY_TYPE PLUMBING
J 0
(200 3950);
DISPLAY 1.234043 (200 3950);
PAINT GREEN (200 3950);
DISPLAY INVISIBLE (200 3950);
FORCEPROP 1 LAST HDL_TAP TRUE
J 0
(525 3875);
DISPLAY 1.234043 (525 3875);
PAINT GREEN (525 3875);
DISPLAY INVISIBLE (525 3875);
FORCEPROP 1 LAST PATH I124
J 0
(198 4000);
DISPLAY 0.872340 (198 4000);
PAINT GREEN (198 4000);
DISPLAY INVISIBLE (198 4000);
FORCEADD TAP..6
(200 3800);
FORCEPROP 3 LASTPIN (250 3800) SIG_NAME M_D_BA<1>
J 0
(260 3810);
DISPLAY 0.659574 (260 3810);
PAINT MONO (260 3810);
DISPLAY INVISIBLE (260 3810);
FORCEPROP 1 LASTPIN (250 3800) BN 1
J 0
(200 3810);
DISPLAY 0.617021 (200 3810);
PAINT PINK (200 3810);
FORCEPROP 2 LAST CDS_LIB mstr_standard
J 0
(200 3800);
DISPLAY 0.787234 (200 3800);
PAINT MONO (200 3800);
DISPLAY INVISIBLE (200 3800);
FORCEPROP 1 LAST BODY_TYPE PLUMBING
J 0
(200 3750);
DISPLAY 1.234043 (200 3750);
PAINT GREEN (200 3750);
DISPLAY INVISIBLE (200 3750);
FORCEPROP 1 LAST HDL_TAP TRUE
J 0
(525 3675);
DISPLAY 1.234043 (525 3675);
PAINT GREEN (525 3675);
DISPLAY INVISIBLE (525 3675);
FORCEPROP 1 LAST PATH I125
J 0
(198 3800);
DISPLAY 0.872340 (198 3800);
PAINT GREEN (198 3800);
DISPLAY INVISIBLE (198 3800);
FORCEADD TAP..6
(200 3650);
FORCEPROP 3 LASTPIN (250 3650) SIG_NAME M_D_BG<0>
J 0
(260 3660);
DISPLAY 0.659574 (260 3660);
PAINT MONO (260 3660);
DISPLAY INVISIBLE (260 3660);
FORCEPROP 1 LASTPIN (250 3650) BN 0
J 0
(200 3660);
DISPLAY 0.617021 (200 3660);
PAINT PINK (200 3660);
FORCEPROP 2 LAST CDS_LIB mstr_standard
J 0
(200 3650);
DISPLAY 0.787234 (200 3650);
PAINT MONO (200 3650);
DISPLAY INVISIBLE (200 3650);
FORCEPROP 1 LAST BODY_TYPE PLUMBING
J 0
(200 3600);
DISPLAY 1.234043 (200 3600);
PAINT GREEN (200 3600);
DISPLAY INVISIBLE (200 3600);
FORCEPROP 1 LAST HDL_TAP TRUE
J 0
(525 3525);
DISPLAY 1.234043 (525 3525);
PAINT GREEN (525 3525);
DISPLAY INVISIBLE (525 3525);
FORCEPROP 1 LAST PATH I126
J 0
(198 3650);
DISPLAY 0.872340 (198 3650);
PAINT GREEN (198 3650);
DISPLAY INVISIBLE (198 3650);
FORCEADD TAP..6
(200 3750);
FORCEPROP 3 LASTPIN (250 3750) SIG_NAME M_D_BA<0>
J 0
(260 3760);
DISPLAY 0.659574 (260 3760);
PAINT MONO (260 3760);
DISPLAY INVISIBLE (260 3760);
FORCEPROP 1 LASTPIN (250 3750) BN 0
J 0
(200 3760);
DISPLAY 0.617021 (200 3760);
PAINT PINK (200 3760);
FORCEPROP 2 LAST CDS_LIB mstr_standard
J 0
(200 3750);
DISPLAY 0.787234 (200 3750);
PAINT MONO (200 3750);
DISPLAY INVISIBLE (200 3750);
FORCEPROP 1 LAST BODY_TYPE PLUMBING
J 0
(200 3700);
DISPLAY 1.234043 (200 3700);
PAINT GREEN (200 3700);
DISPLAY INVISIBLE (200 3700);
FORCEPROP 1 LAST HDL_TAP TRUE
J 0
(525 3625);
DISPLAY 1.234043 (525 3625);
PAINT GREEN (525 3625);
DISPLAY INVISIBLE (525 3625);
FORCEPROP 1 LAST PATH I127
J 0
(198 3750);
DISPLAY 0.872340 (198 3750);
PAINT GREEN (198 3750);
DISPLAY INVISIBLE (198 3750);
FORCEADD TAP..6
(200 3700);
FORCEPROP 3 LASTPIN (250 3700) SIG_NAME M_D_BG<1>
J 0
(260 3710);
DISPLAY 0.659574 (260 3710);
PAINT MONO (260 3710);
DISPLAY INVISIBLE (260 3710);
FORCEPROP 1 LASTPIN (250 3700) BN 1
J 0
(200 3710);
DISPLAY 0.617021 (200 3710);
PAINT PINK (200 3710);
FORCEPROP 2 LAST CDS_LIB mstr_standard
J 0
(200 3700);
DISPLAY 0.787234 (200 3700);
PAINT MONO (200 3700);
DISPLAY INVISIBLE (200 3700);
FORCEPROP 1 LAST BODY_TYPE PLUMBING
J 0
(200 3650);
DISPLAY 1.234043 (200 3650);
PAINT GREEN (200 3650);
DISPLAY INVISIBLE (200 3650);
FORCEPROP 1 LAST HDL_TAP TRUE
J 0
(525 3575);
DISPLAY 1.234043 (525 3575);
PAINT GREEN (525 3575);
DISPLAY INVISIBLE (525 3575);
FORCEPROP 1 LAST PATH I128
J 0
(198 3700);
DISPLAY 0.872340 (198 3700);
PAINT GREEN (198 3700);
DISPLAY INVISIBLE (198 3700);
FORCEADD TAP..6
(200 3550);
FORCEPROP 3 LASTPIN (250 3550) SIG_NAME M_D_CLK_DP<3>
J 0
(260 3560);
DISPLAY 0.659574 (260 3560);
PAINT MONO (260 3560);
DISPLAY INVISIBLE (260 3560);
FORCEPROP 1 LASTPIN (250 3550) BN 3
J 0
(200 3560);
DISPLAY 0.617021 (200 3560);
PAINT PINK (200 3560);
FORCEPROP 2 LAST CDS_LIB mstr_standard
J 0
(200 3550);
DISPLAY 0.787234 (200 3550);
PAINT MONO (200 3550);
DISPLAY INVISIBLE (200 3550);
FORCEPROP 1 LAST BODY_TYPE PLUMBING
J 0
(200 3500);
DISPLAY 1.234043 (200 3500);
PAINT GREEN (200 3500);
DISPLAY INVISIBLE (200 3500);
FORCEPROP 1 LAST HDL_TAP TRUE
J 0
(525 3425);
DISPLAY 1.234043 (525 3425);
PAINT GREEN (525 3425);
DISPLAY INVISIBLE (525 3425);
FORCEPROP 1 LAST PATH I129
J 0
(198 3550);
DISPLAY 0.872340 (198 3550);
PAINT GREEN (198 3550);
DISPLAY INVISIBLE (198 3550);
FORCEADD TAP..6
R 2
(4350 4150);
FORCEPROP 3 LASTPIN (4300 4150) SIG_NAME M_D_DQS_DN<11>
J 0
(4310 4160);
DISPLAY 0.659574 (4310 4160);
PAINT MONO (4310 4160);
DISPLAY INVISIBLE (4310 4160);
FORCEPROP 1 LASTPIN (4300 4150) BN 11
J 2
(4350 4160);
DISPLAY 0.617021 (4350 4160);
PAINT PINK (4350 4160);
FORCEPROP 2 LAST CDS_LIB mstr_standard
J 0
(4350 4150);
DISPLAY 0.787234 (4350 4150);
PAINT MONO (4350 4150);
DISPLAY INVISIBLE (4350 4150);
FORCEPROP 1 LAST BODY_TYPE PLUMBING
J 2
(4350 4100);
DISPLAY 1.234043 (4350 4100);
PAINT GREEN (4350 4100);
DISPLAY INVISIBLE (4350 4100);
FORCEPROP 1 LAST HDL_TAP TRUE
J 2
(4025 4025);
DISPLAY 1.234043 (4025 4025);
PAINT GREEN (4025 4025);
DISPLAY INVISIBLE (4025 4025);
FORCEPROP 1 LAST PATH I13
J 2
(4352 4150);
DISPLAY 0.872340 (4352 4150);
PAINT GREEN (4352 4150);
DISPLAY INVISIBLE (4352 4150);
FORCEADD TAP..6
(200 3450);
FORCEPROP 3 LASTPIN (250 3450) SIG_NAME M_D_CLK_DP<2>
J 0
(260 3460);
DISPLAY 0.659574 (260 3460);
PAINT MONO (260 3460);
DISPLAY INVISIBLE (260 3460);
FORCEPROP 1 LASTPIN (250 3450) BN 2
J 0
(200 3460);
DISPLAY 0.617021 (200 3460);
PAINT PINK (200 3460);
FORCEPROP 2 LAST CDS_LIB mstr_standard
J 0
(200 3450);
DISPLAY 0.787234 (200 3450);
PAINT MONO (200 3450);
DISPLAY INVISIBLE (200 3450);
FORCEPROP 1 LAST BODY_TYPE PLUMBING
J 0
(200 3400);
DISPLAY 1.234043 (200 3400);
PAINT GREEN (200 3400);
DISPLAY INVISIBLE (200 3400);
FORCEPROP 1 LAST HDL_TAP TRUE
J 0
(525 3325);
DISPLAY 1.234043 (525 3325);
PAINT GREEN (525 3325);
DISPLAY INVISIBLE (525 3325);
FORCEPROP 1 LAST PATH I130
J 0
(198 3450);
DISPLAY 0.872340 (198 3450);
PAINT GREEN (198 3450);
DISPLAY INVISIBLE (198 3450);
FORCEADD TAP..6
(200 3250);
FORCEPROP 3 LASTPIN (250 3250) SIG_NAME M_D_CS_N<7>
J 0
(260 3260);
DISPLAY 0.659574 (260 3260);
PAINT MONO (260 3260);
DISPLAY INVISIBLE (260 3260);
FORCEPROP 1 LASTPIN (250 3250) BN 7
J 0
(200 3260);
DISPLAY 0.617021 (200 3260);
PAINT PINK (200 3260);
FORCEPROP 2 LAST CDS_LIB mstr_standard
J 0
(200 3250);
DISPLAY 0.787234 (200 3250);
PAINT MONO (200 3250);
DISPLAY INVISIBLE (200 3250);
FORCEPROP 1 LAST BODY_TYPE PLUMBING
J 0
(200 3200);
DISPLAY 1.234043 (200 3200);
PAINT GREEN (200 3200);
DISPLAY INVISIBLE (200 3200);
FORCEPROP 1 LAST HDL_TAP TRUE
J 0
(525 3125);
DISPLAY 1.234043 (525 3125);
PAINT GREEN (525 3125);
DISPLAY INVISIBLE (525 3125);
FORCEPROP 1 LAST PATH I131
J 0
(198 3250);
DISPLAY 0.872340 (198 3250);
PAINT GREEN (198 3250);
DISPLAY INVISIBLE (198 3250);
FORCEADD TAP..6
(200 3200);
FORCEPROP 3 LASTPIN (250 3200) SIG_NAME M_D_CS_N<6>
J 0
(260 3210);
DISPLAY 0.659574 (260 3210);
PAINT MONO (260 3210);
DISPLAY INVISIBLE (260 3210);
FORCEPROP 1 LASTPIN (250 3200) BN 6
J 0
(200 3210);
DISPLAY 0.617021 (200 3210);
PAINT PINK (200 3210);
FORCEPROP 2 LAST CDS_LIB mstr_standard
J 0
(200 3200);
DISPLAY 0.787234 (200 3200);
PAINT MONO (200 3200);
DISPLAY INVISIBLE (200 3200);
FORCEPROP 1 LAST BODY_TYPE PLUMBING
J 0
(200 3150);
DISPLAY 1.234043 (200 3150);
PAINT GREEN (200 3150);
DISPLAY INVISIBLE (200 3150);
FORCEPROP 1 LAST HDL_TAP TRUE
J 0
(525 3075);
DISPLAY 1.234043 (525 3075);
PAINT GREEN (525 3075);
DISPLAY INVISIBLE (525 3075);
FORCEPROP 1 LAST PATH I132
J 0
(198 3200);
DISPLAY 0.872340 (198 3200);
PAINT GREEN (198 3200);
DISPLAY INVISIBLE (198 3200);
FORCEADD TAP..6
(200 3150);
FORCEPROP 3 LASTPIN (250 3150) SIG_NAME M_D_CS_N<5>
J 0
(260 3160);
DISPLAY 0.659574 (260 3160);
PAINT MONO (260 3160);
DISPLAY INVISIBLE (260 3160);
FORCEPROP 1 LASTPIN (250 3150) BN 5
J 0
(200 3160);
DISPLAY 0.617021 (200 3160);
PAINT PINK (200 3160);
FORCEPROP 2 LAST CDS_LIB mstr_standard
J 0
(200 3150);
DISPLAY 0.787234 (200 3150);
PAINT MONO (200 3150);
DISPLAY INVISIBLE (200 3150);
FORCEPROP 1 LAST BODY_TYPE PLUMBING
J 0
(200 3100);
DISPLAY 1.234043 (200 3100);
PAINT GREEN (200 3100);
DISPLAY INVISIBLE (200 3100);
FORCEPROP 1 LAST HDL_TAP TRUE
J 0
(525 3025);
DISPLAY 1.234043 (525 3025);
PAINT GREEN (525 3025);
DISPLAY INVISIBLE (525 3025);
FORCEPROP 1 LAST PATH I133
J 0
(198 3150);
DISPLAY 0.872340 (198 3150);
PAINT GREEN (198 3150);
DISPLAY INVISIBLE (198 3150);
FORCEADD TAP..6
(200 3100);
FORCEPROP 3 LASTPIN (250 3100) SIG_NAME M_D_CS_N<4>
J 0
(260 3110);
DISPLAY 0.659574 (260 3110);
PAINT MONO (260 3110);
DISPLAY INVISIBLE (260 3110);
FORCEPROP 1 LASTPIN (250 3100) BN 4
J 0
(200 3110);
DISPLAY 0.617021 (200 3110);
PAINT PINK (200 3110);
FORCEPROP 2 LAST CDS_LIB mstr_standard
J 0
(200 3100);
DISPLAY 0.787234 (200 3100);
PAINT MONO (200 3100);
DISPLAY INVISIBLE (200 3100);
FORCEPROP 1 LAST BODY_TYPE PLUMBING
J 0
(200 3050);
DISPLAY 1.234043 (200 3050);
PAINT GREEN (200 3050);
DISPLAY INVISIBLE (200 3050);
FORCEPROP 1 LAST HDL_TAP TRUE
J 0
(525 2975);
DISPLAY 1.234043 (525 2975);
PAINT GREEN (525 2975);
DISPLAY INVISIBLE (525 2975);
FORCEPROP 1 LAST PATH I134
J 0
(198 3100);
DISPLAY 0.872340 (198 3100);
PAINT GREEN (198 3100);
DISPLAY INVISIBLE (198 3100);
FORCEADD TAP..6
(0 3500);
FORCEPROP 3 LASTPIN (50 3500) SIG_NAME M_D_CLK_DN<3>
J 0
(60 3510);
DISPLAY 0.659574 (60 3510);
PAINT MONO (60 3510);
DISPLAY INVISIBLE (60 3510);
FORCEPROP 1 LASTPIN (50 3500) BN 3
J 0
(0 3510);
DISPLAY 0.617021 (0 3510);
PAINT PINK (0 3510);
FORCEPROP 2 LAST CDS_LIB mstr_standard
J 0
(0 3500);
DISPLAY 0.787234 (0 3500);
PAINT MONO (0 3500);
DISPLAY INVISIBLE (0 3500);
FORCEPROP 1 LAST BODY_TYPE PLUMBING
J 0
(0 3450);
DISPLAY 1.234043 (0 3450);
PAINT GREEN (0 3450);
DISPLAY INVISIBLE (0 3450);
FORCEPROP 1 LAST HDL_TAP TRUE
J 0
(325 3375);
DISPLAY 1.234043 (325 3375);
PAINT GREEN (325 3375);
DISPLAY INVISIBLE (325 3375);
FORCEPROP 1 LAST PATH I135
J 0
(-2 3500);
DISPLAY 0.872340 (-2 3500);
PAINT GREEN (-2 3500);
DISPLAY INVISIBLE (-2 3500);
FORCEADD TAP..6
(0 3400);
FORCEPROP 3 LASTPIN (50 3400) SIG_NAME M_D_CLK_DN<2>
J 0
(60 3410);
DISPLAY 0.659574 (60 3410);
PAINT MONO (60 3410);
DISPLAY INVISIBLE (60 3410);
FORCEPROP 1 LASTPIN (50 3400) BN 2
J 0
(0 3410);
DISPLAY 0.617021 (0 3410);
PAINT PINK (0 3410);
FORCEPROP 2 LAST CDS_LIB mstr_standard
J 0
(0 3400);
DISPLAY 0.787234 (0 3400);
PAINT MONO (0 3400);
DISPLAY INVISIBLE (0 3400);
FORCEPROP 1 LAST BODY_TYPE PLUMBING
J 0
(0 3350);
DISPLAY 1.234043 (0 3350);
PAINT GREEN (0 3350);
DISPLAY INVISIBLE (0 3350);
FORCEPROP 1 LAST HDL_TAP TRUE
J 0
(325 3275);
DISPLAY 1.234043 (325 3275);
PAINT GREEN (325 3275);
DISPLAY INVISIBLE (325 3275);
FORCEPROP 1 LAST PATH I136
J 0
(-2 3400);
DISPLAY 0.872340 (-2 3400);
PAINT GREEN (-2 3400);
DISPLAY INVISIBLE (-2 3400);
FORCEADD TAP..6
(200 2800);
FORCEPROP 3 LASTPIN (250 2800) SIG_NAME M_D_ODT<2>
J 0
(260 2810);
DISPLAY 0.659574 (260 2810);
PAINT MONO (260 2810);
DISPLAY INVISIBLE (260 2810);
FORCEPROP 1 LASTPIN (250 2800) BN 2
J 0
(200 2810);
DISPLAY 0.617021 (200 2810);
PAINT PINK (200 2810);
FORCEPROP 2 LAST CDS_LIB mstr_standard
J 0
(200 2800);
DISPLAY 0.787234 (200 2800);
PAINT MONO (200 2800);
DISPLAY INVISIBLE (200 2800);
FORCEPROP 1 LAST BODY_TYPE PLUMBING
J 0
(200 2750);
DISPLAY 1.234043 (200 2750);
PAINT GREEN (200 2750);
DISPLAY INVISIBLE (200 2750);
FORCEPROP 1 LAST HDL_TAP TRUE
J 0
(525 2675);
DISPLAY 1.234043 (525 2675);
PAINT GREEN (525 2675);
DISPLAY INVISIBLE (525 2675);
FORCEPROP 1 LAST PATH I137
J 0
(198 2800);
DISPLAY 0.872340 (198 2800);
PAINT GREEN (198 2800);
DISPLAY INVISIBLE (198 2800);
FORCEADD TAP..6
(200 2950);
FORCEPROP 3 LASTPIN (250 2950) SIG_NAME M_D_CKE<2>
J 0
(260 2960);
DISPLAY 0.659574 (260 2960);
PAINT MONO (260 2960);
DISPLAY INVISIBLE (260 2960);
FORCEPROP 1 LASTPIN (250 2950) BN 2
J 0
(200 2960);
DISPLAY 0.617021 (200 2960);
PAINT PINK (200 2960);
FORCEPROP 2 LAST CDS_LIB mstr_standard
J 0
(200 2950);
DISPLAY 0.787234 (200 2950);
PAINT MONO (200 2950);
DISPLAY INVISIBLE (200 2950);
FORCEPROP 1 LAST BODY_TYPE PLUMBING
J 0
(200 2900);
DISPLAY 1.234043 (200 2900);
PAINT GREEN (200 2900);
DISPLAY INVISIBLE (200 2900);
FORCEPROP 1 LAST HDL_TAP TRUE
J 0
(525 2825);
DISPLAY 1.234043 (525 2825);
PAINT GREEN (525 2825);
DISPLAY INVISIBLE (525 2825);
FORCEPROP 1 LAST PATH I138
J 0
(198 2950);
DISPLAY 0.872340 (198 2950);
PAINT GREEN (198 2950);
DISPLAY INVISIBLE (198 2950);
FORCEADD TAP..6
(200 3000);
FORCEPROP 3 LASTPIN (250 3000) SIG_NAME M_D_CKE<3>
J 0
(260 3010);
DISPLAY 0.659574 (260 3010);
PAINT MONO (260 3010);
DISPLAY INVISIBLE (260 3010);
FORCEPROP 1 LASTPIN (250 3000) BN 3
J 0
(200 3010);
DISPLAY 0.617021 (200 3010);
PAINT PINK (200 3010);
FORCEPROP 2 LAST CDS_LIB mstr_standard
J 0
(200 3000);
DISPLAY 0.787234 (200 3000);
PAINT MONO (200 3000);
DISPLAY INVISIBLE (200 3000);
FORCEPROP 1 LAST BODY_TYPE PLUMBING
J 0
(200 2950);
DISPLAY 1.234043 (200 2950);
PAINT GREEN (200 2950);
DISPLAY INVISIBLE (200 2950);
FORCEPROP 1 LAST HDL_TAP TRUE
J 0
(525 2875);
DISPLAY 1.234043 (525 2875);
PAINT GREEN (525 2875);
DISPLAY INVISIBLE (525 2875);
FORCEPROP 1 LAST PATH I139
J 0
(198 3000);
DISPLAY 0.872340 (198 3000);
PAINT GREEN (198 3000);
DISPLAY INVISIBLE (198 3000);
FORCEADD TAP..6
R 2
(4100 4500);
FORCEPROP 3 LASTPIN (4050 4500) SIG_NAME M_D_DQS_DP<14>
J 0
(4060 4510);
DISPLAY 0.659574 (4060 4510);
PAINT MONO (4060 4510);
DISPLAY INVISIBLE (4060 4510);
FORCEPROP 1 LASTPIN (4050 4500) BN 14
J 2
(4100 4510);
DISPLAY 0.617021 (4100 4510);
PAINT PINK (4100 4510);
FORCEPROP 2 LAST CDS_LIB mstr_standard
J 0
(4100 4500);
DISPLAY 0.787234 (4100 4500);
PAINT MONO (4100 4500);
DISPLAY INVISIBLE (4100 4500);
FORCEPROP 1 LAST BODY_TYPE PLUMBING
J 2
(4100 4450);
DISPLAY 1.234043 (4100 4450);
PAINT GREEN (4100 4450);
DISPLAY INVISIBLE (4100 4450);
FORCEPROP 1 LAST HDL_TAP TRUE
J 2
(3775 4375);
DISPLAY 1.234043 (3775 4375);
PAINT GREEN (3775 4375);
DISPLAY INVISIBLE (3775 4375);
FORCEPROP 1 LAST PATH I14
J 2
(4102 4500);
DISPLAY 0.872340 (4102 4500);
PAINT GREEN (4102 4500);
DISPLAY INVISIBLE (4102 4500);
FORCEADD TAP..6
(200 2850);
FORCEPROP 3 LASTPIN (250 2850) SIG_NAME M_D_ODT<3>
J 0
(260 2860);
DISPLAY 0.659574 (260 2860);
PAINT MONO (260 2860);
DISPLAY INVISIBLE (260 2860);
FORCEPROP 1 LASTPIN (250 2850) BN 3
J 0
(200 2860);
DISPLAY 0.617021 (200 2860);
PAINT PINK (200 2860);
FORCEPROP 2 LAST CDS_LIB mstr_standard
J 0
(200 2850);
DISPLAY 0.787234 (200 2850);
PAINT MONO (200 2850);
DISPLAY INVISIBLE (200 2850);
FORCEPROP 1 LAST BODY_TYPE PLUMBING
J 0
(200 2800);
DISPLAY 1.234043 (200 2800);
PAINT GREEN (200 2800);
DISPLAY INVISIBLE (200 2800);
FORCEPROP 1 LAST HDL_TAP TRUE
J 0
(525 2725);
DISPLAY 1.234043 (525 2725);
PAINT GREEN (525 2725);
DISPLAY INVISIBLE (525 2725);
FORCEPROP 1 LAST PATH I140
J 0
(198 2850);
DISPLAY 0.872340 (198 2850);
PAINT GREEN (198 2850);
DISPLAY INVISIBLE (198 2850);
FORCEADD TAP..6
(200 2650);
FORCEPROP 3 LASTPIN (250 2650) SIG_NAME M_D_ECC<6>
J 0
(260 2660);
DISPLAY 0.659574 (260 2660);
PAINT MONO (260 2660);
DISPLAY INVISIBLE (260 2660);
FORCEPROP 1 LASTPIN (250 2650) BN 6
J 0
(200 2660);
DISPLAY 0.617021 (200 2660);
PAINT PINK (200 2660);
FORCEPROP 2 LAST CDS_LIB mstr_standard
J 0
(200 2650);
DISPLAY 0.787234 (200 2650);
PAINT MONO (200 2650);
DISPLAY INVISIBLE (200 2650);
FORCEPROP 1 LAST BODY_TYPE PLUMBING
J 0
(200 2600);
DISPLAY 1.234043 (200 2600);
PAINT GREEN (200 2600);
DISPLAY INVISIBLE (200 2600);
FORCEPROP 1 LAST HDL_TAP TRUE
J 0
(525 2525);
DISPLAY 1.234043 (525 2525);
PAINT GREEN (525 2525);
DISPLAY INVISIBLE (525 2525);
FORCEPROP 1 LAST PATH I141
J 0
(198 2650);
DISPLAY 0.872340 (198 2650);
PAINT GREEN (198 2650);
DISPLAY INVISIBLE (198 2650);
FORCEADD TAP..6
(200 2700);
FORCEPROP 3 LASTPIN (250 2700) SIG_NAME M_D_ECC<7>
J 0
(260 2710);
DISPLAY 0.659574 (260 2710);
PAINT MONO (260 2710);
DISPLAY INVISIBLE (260 2710);
FORCEPROP 1 LASTPIN (250 2700) BN 7
J 0
(200 2710);
DISPLAY 0.617021 (200 2710);
PAINT PINK (200 2710);
FORCEPROP 2 LAST CDS_LIB mstr_standard
J 0
(200 2700);
DISPLAY 0.787234 (200 2700);
PAINT MONO (200 2700);
DISPLAY INVISIBLE (200 2700);
FORCEPROP 1 LAST BODY_TYPE PLUMBING
J 0
(200 2650);
DISPLAY 1.234043 (200 2650);
PAINT GREEN (200 2650);
DISPLAY INVISIBLE (200 2650);
FORCEPROP 1 LAST HDL_TAP TRUE
J 0
(525 2575);
DISPLAY 1.234043 (525 2575);
PAINT GREEN (525 2575);
DISPLAY INVISIBLE (525 2575);
FORCEPROP 1 LAST PATH I142
J 0
(198 2700);
DISPLAY 0.872340 (198 2700);
PAINT GREEN (198 2700);
DISPLAY INVISIBLE (198 2700);
FORCEADD TAP..6
(200 2600);
FORCEPROP 3 LASTPIN (250 2600) SIG_NAME M_D_ECC<5>
J 0
(260 2610);
DISPLAY 0.659574 (260 2610);
PAINT MONO (260 2610);
DISPLAY INVISIBLE (260 2610);
FORCEPROP 1 LASTPIN (250 2600) BN 5
J 0
(200 2610);
DISPLAY 0.617021 (200 2610);
PAINT PINK (200 2610);
FORCEPROP 2 LAST CDS_LIB mstr_standard
J 0
(200 2600);
DISPLAY 0.787234 (200 2600);
PAINT MONO (200 2600);
DISPLAY INVISIBLE (200 2600);
FORCEPROP 1 LAST BODY_TYPE PLUMBING
J 0
(200 2550);
DISPLAY 1.234043 (200 2550);
PAINT GREEN (200 2550);
DISPLAY INVISIBLE (200 2550);
FORCEPROP 1 LAST HDL_TAP TRUE
J 0
(525 2475);
DISPLAY 1.234043 (525 2475);
PAINT GREEN (525 2475);
DISPLAY INVISIBLE (525 2475);
FORCEPROP 1 LAST PATH I143
J 0
(198 2600);
DISPLAY 0.872340 (198 2600);
PAINT GREEN (198 2600);
DISPLAY INVISIBLE (198 2600);
FORCEADD TAP..6
(200 2550);
FORCEPROP 3 LASTPIN (250 2550) SIG_NAME M_D_ECC<4>
J 0
(260 2560);
DISPLAY 0.659574 (260 2560);
PAINT MONO (260 2560);
DISPLAY INVISIBLE (260 2560);
FORCEPROP 1 LASTPIN (250 2550) BN 4
J 0
(200 2560);
DISPLAY 0.617021 (200 2560);
PAINT PINK (200 2560);
FORCEPROP 2 LAST CDS_LIB mstr_standard
J 0
(200 2550);
DISPLAY 0.787234 (200 2550);
PAINT MONO (200 2550);
DISPLAY INVISIBLE (200 2550);
FORCEPROP 1 LAST BODY_TYPE PLUMBING
J 0
(200 2500);
DISPLAY 1.234043 (200 2500);
PAINT GREEN (200 2500);
DISPLAY INVISIBLE (200 2500);
FORCEPROP 1 LAST HDL_TAP TRUE
J 0
(525 2425);
DISPLAY 1.234043 (525 2425);
PAINT GREEN (525 2425);
DISPLAY INVISIBLE (525 2425);
FORCEPROP 1 LAST PATH I144
J 0
(198 2550);
DISPLAY 0.872340 (198 2550);
PAINT GREEN (198 2550);
DISPLAY INVISIBLE (198 2550);
FORCEADD TAP..6
(200 2350);
FORCEPROP 3 LASTPIN (250 2350) SIG_NAME M_D_ECC<0>
J 0
(260 2360);
DISPLAY 0.659574 (260 2360);
PAINT MONO (260 2360);
DISPLAY INVISIBLE (260 2360);
FORCEPROP 1 LASTPIN (250 2350) BN 0
J 0
(200 2360);
DISPLAY 0.617021 (200 2360);
PAINT PINK (200 2360);
FORCEPROP 2 LAST CDS_LIB mstr_standard
J 0
(200 2350);
DISPLAY 0.787234 (200 2350);
PAINT MONO (200 2350);
DISPLAY INVISIBLE (200 2350);
FORCEPROP 1 LAST BODY_TYPE PLUMBING
J 0
(200 2300);
DISPLAY 1.234043 (200 2300);
PAINT GREEN (200 2300);
DISPLAY INVISIBLE (200 2300);
FORCEPROP 1 LAST HDL_TAP TRUE
J 0
(525 2225);
DISPLAY 1.234043 (525 2225);
PAINT GREEN (525 2225);
DISPLAY INVISIBLE (525 2225);
FORCEPROP 1 LAST PATH I145
J 0
(198 2350);
DISPLAY 0.872340 (198 2350);
PAINT GREEN (198 2350);
DISPLAY INVISIBLE (198 2350);
FORCEADD TAP..6
(200 2400);
FORCEPROP 3 LASTPIN (250 2400) SIG_NAME M_D_ECC<1>
J 0
(260 2410);
DISPLAY 0.659574 (260 2410);
PAINT MONO (260 2410);
DISPLAY INVISIBLE (260 2410);
FORCEPROP 1 LASTPIN (250 2400) BN 1
J 0
(200 2410);
DISPLAY 0.617021 (200 2410);
PAINT PINK (200 2410);
FORCEPROP 2 LAST CDS_LIB mstr_standard
J 0
(200 2400);
DISPLAY 0.787234 (200 2400);
PAINT MONO (200 2400);
DISPLAY INVISIBLE (200 2400);
FORCEPROP 1 LAST BODY_TYPE PLUMBING
J 0
(200 2350);
DISPLAY 1.234043 (200 2350);
PAINT GREEN (200 2350);
DISPLAY INVISIBLE (200 2350);
FORCEPROP 1 LAST HDL_TAP TRUE
J 0
(525 2275);
DISPLAY 1.234043 (525 2275);
PAINT GREEN (525 2275);
DISPLAY INVISIBLE (525 2275);
FORCEPROP 1 LAST PATH I146
J 0
(198 2400);
DISPLAY 0.872340 (198 2400);
PAINT GREEN (198 2400);
DISPLAY INVISIBLE (198 2400);
FORCEADD TAP..6
(200 2450);
FORCEPROP 3 LASTPIN (250 2450) SIG_NAME M_D_ECC<2>
J 0
(260 2460);
DISPLAY 0.659574 (260 2460);
PAINT MONO (260 2460);
DISPLAY INVISIBLE (260 2460);
FORCEPROP 1 LASTPIN (250 2450) BN 2
J 0
(200 2460);
DISPLAY 0.617021 (200 2460);
PAINT PINK (200 2460);
FORCEPROP 2 LAST CDS_LIB mstr_standard
J 0
(200 2450);
DISPLAY 0.787234 (200 2450);
PAINT MONO (200 2450);
DISPLAY INVISIBLE (200 2450);
FORCEPROP 1 LAST BODY_TYPE PLUMBING
J 0
(200 2400);
DISPLAY 1.234043 (200 2400);
PAINT GREEN (200 2400);
DISPLAY INVISIBLE (200 2400);
FORCEPROP 1 LAST HDL_TAP TRUE
J 0
(525 2325);
DISPLAY 1.234043 (525 2325);
PAINT GREEN (525 2325);
DISPLAY INVISIBLE (525 2325);
FORCEPROP 1 LAST PATH I147
J 0
(198 2450);
DISPLAY 0.872340 (198 2450);
PAINT GREEN (198 2450);
DISPLAY INVISIBLE (198 2450);
FORCEADD TAP..6
(200 2500);
FORCEPROP 3 LASTPIN (250 2500) SIG_NAME M_D_ECC<3>
J 0
(260 2510);
DISPLAY 0.659574 (260 2510);
PAINT MONO (260 2510);
DISPLAY INVISIBLE (260 2510);
FORCEPROP 1 LASTPIN (250 2500) BN 3
J 0
(200 2510);
DISPLAY 0.617021 (200 2510);
PAINT PINK (200 2510);
FORCEPROP 2 LAST CDS_LIB mstr_standard
J 0
(200 2500);
DISPLAY 0.787234 (200 2500);
PAINT MONO (200 2500);
DISPLAY INVISIBLE (200 2500);
FORCEPROP 1 LAST BODY_TYPE PLUMBING
J 0
(200 2450);
DISPLAY 1.234043 (200 2450);
PAINT GREEN (200 2450);
DISPLAY INVISIBLE (200 2450);
FORCEPROP 1 LAST HDL_TAP TRUE
J 0
(525 2375);
DISPLAY 1.234043 (525 2375);
PAINT GREEN (525 2375);
DISPLAY INVISIBLE (525 2375);
FORCEPROP 1 LAST PATH I148
J 0
(198 2500);
DISPLAY 0.872340 (198 2500);
PAINT GREEN (198 2500);
DISPLAY INVISIBLE (198 2500);
FORCEADD TAP..6
R 2
(1700 1850);
FORCEPROP 3 LASTPIN (1650 1850) SIG_NAME M_D_DQ<5>
J 0
(1660 1860);
DISPLAY 0.659574 (1660 1860);
PAINT MONO (1660 1860);
DISPLAY INVISIBLE (1660 1860);
FORCEPROP 1 LASTPIN (1650 1850) BN 5
J 2
(1700 1860);
DISPLAY 0.617021 (1700 1860);
PAINT PINK (1700 1860);
FORCEPROP 2 LAST CDS_LIB mstr_standard
J 2
(1700 1850);
DISPLAY 0.787234 (1700 1850);
PAINT MONO (1700 1850);
DISPLAY INVISIBLE (1700 1850);
FORCEPROP 1 LAST BODY_TYPE PLUMBING
J 2
(1700 1800);
DISPLAY 1.234043 (1700 1800);
PAINT GREEN (1700 1800);
DISPLAY INVISIBLE (1700 1800);
FORCEPROP 1 LAST HDL_TAP TRUE
J 2
(1375 1725);
DISPLAY 1.234043 (1375 1725);
PAINT GREEN (1375 1725);
DISPLAY INVISIBLE (1375 1725);
FORCEPROP 1 LAST PATH I149
J 2
(1702 1850);
DISPLAY 0.872340 (1702 1850);
PAINT GREEN (1702 1850);
DISPLAY INVISIBLE (1702 1850);
FORCEADD TAP..6
R 2
(4100 4400);
FORCEPROP 3 LASTPIN (4050 4400) SIG_NAME M_D_DQS_DP<13>
J 0
(4060 4410);
DISPLAY 0.659574 (4060 4410);
PAINT MONO (4060 4410);
DISPLAY INVISIBLE (4060 4410);
FORCEPROP 1 LASTPIN (4050 4400) BN 13
J 2
(4100 4410);
DISPLAY 0.617021 (4100 4410);
PAINT PINK (4100 4410);
FORCEPROP 2 LAST CDS_LIB mstr_standard
J 0
(4100 4400);
DISPLAY 0.787234 (4100 4400);
PAINT MONO (4100 4400);
DISPLAY INVISIBLE (4100 4400);
FORCEPROP 1 LAST BODY_TYPE PLUMBING
J 2
(4100 4350);
DISPLAY 1.234043 (4100 4350);
PAINT GREEN (4100 4350);
DISPLAY INVISIBLE (4100 4350);
FORCEPROP 1 LAST HDL_TAP TRUE
J 2
(3775 4275);
DISPLAY 1.234043 (3775 4275);
PAINT GREEN (3775 4275);
DISPLAY INVISIBLE (3775 4275);
FORCEPROP 1 LAST PATH I15
J 2
(4102 4400);
DISPLAY 0.872340 (4102 4400);
PAINT GREEN (4102 4400);
DISPLAY INVISIBLE (4102 4400);
FORCEADD TAP..6
R 2
(1700 1800);
FORCEPROP 3 LASTPIN (1650 1800) SIG_NAME M_D_DQ<4>
J 0
(1660 1810);
DISPLAY 0.659574 (1660 1810);
PAINT MONO (1660 1810);
DISPLAY INVISIBLE (1660 1810);
FORCEPROP 1 LASTPIN (1650 1800) BN 4
J 2
(1700 1810);
DISPLAY 0.617021 (1700 1810);
PAINT PINK (1700 1810);
FORCEPROP 2 LAST CDS_LIB mstr_standard
J 2
(1700 1800);
DISPLAY 0.787234 (1700 1800);
PAINT MONO (1700 1800);
DISPLAY INVISIBLE (1700 1800);
FORCEPROP 1 LAST BODY_TYPE PLUMBING
J 2
(1700 1750);
DISPLAY 1.234043 (1700 1750);
PAINT GREEN (1700 1750);
DISPLAY INVISIBLE (1700 1750);
FORCEPROP 1 LAST HDL_TAP TRUE
J 2
(1375 1675);
DISPLAY 1.234043 (1375 1675);
PAINT GREEN (1375 1675);
DISPLAY INVISIBLE (1375 1675);
FORCEPROP 1 LAST PATH I150
J 2
(1702 1800);
DISPLAY 0.872340 (1702 1800);
PAINT GREEN (1702 1800);
DISPLAY INVISIBLE (1702 1800);
FORCEADD TAP..6
R 2
(1700 1950);
FORCEPROP 3 LASTPIN (1650 1950) SIG_NAME M_D_DQ<7>
J 0
(1660 1960);
DISPLAY 0.659574 (1660 1960);
PAINT MONO (1660 1960);
DISPLAY INVISIBLE (1660 1960);
FORCEPROP 1 LASTPIN (1650 1950) BN 7
J 2
(1700 1960);
DISPLAY 0.617021 (1700 1960);
PAINT PINK (1700 1960);
FORCEPROP 2 LAST CDS_LIB mstr_standard
J 2
(1700 1950);
DISPLAY 0.787234 (1700 1950);
PAINT MONO (1700 1950);
DISPLAY INVISIBLE (1700 1950);
FORCEPROP 1 LAST BODY_TYPE PLUMBING
J 2
(1700 1900);
DISPLAY 1.234043 (1700 1900);
PAINT GREEN (1700 1900);
DISPLAY INVISIBLE (1700 1900);
FORCEPROP 1 LAST HDL_TAP TRUE
J 2
(1375 1825);
DISPLAY 1.234043 (1375 1825);
PAINT GREEN (1375 1825);
DISPLAY INVISIBLE (1375 1825);
FORCEPROP 1 LAST PATH I151
J 2
(1702 1950);
DISPLAY 0.872340 (1702 1950);
PAINT GREEN (1702 1950);
DISPLAY INVISIBLE (1702 1950);
FORCEADD TAP..6
R 2
(1700 2000);
FORCEPROP 3 LASTPIN (1650 2000) SIG_NAME M_D_DQ<8>
J 0
(1660 2010);
DISPLAY 0.659574 (1660 2010);
PAINT MONO (1660 2010);
DISPLAY INVISIBLE (1660 2010);
FORCEPROP 1 LASTPIN (1650 2000) BN 8
J 2
(1700 2010);
DISPLAY 0.617021 (1700 2010);
PAINT PINK (1700 2010);
FORCEPROP 2 LAST CDS_LIB mstr_standard
J 2
(1700 2000);
DISPLAY 0.787234 (1700 2000);
PAINT MONO (1700 2000);
DISPLAY INVISIBLE (1700 2000);
FORCEPROP 1 LAST BODY_TYPE PLUMBING
J 2
(1700 1950);
DISPLAY 1.234043 (1700 1950);
PAINT GREEN (1700 1950);
DISPLAY INVISIBLE (1700 1950);
FORCEPROP 1 LAST HDL_TAP TRUE
J 2
(1375 1875);
DISPLAY 1.234043 (1375 1875);
PAINT GREEN (1375 1875);
DISPLAY INVISIBLE (1375 1875);
FORCEPROP 1 LAST PATH I152
J 2
(1702 2000);
DISPLAY 0.872340 (1702 2000);
PAINT GREEN (1702 2000);
DISPLAY INVISIBLE (1702 2000);
FORCEADD TAP..6
R 2
(1700 1900);
FORCEPROP 3 LASTPIN (1650 1900) SIG_NAME M_D_DQ<6>
J 0
(1660 1910);
DISPLAY 0.659574 (1660 1910);
PAINT MONO (1660 1910);
DISPLAY INVISIBLE (1660 1910);
FORCEPROP 1 LASTPIN (1650 1900) BN 6
J 2
(1700 1910);
DISPLAY 0.617021 (1700 1910);
PAINT PINK (1700 1910);
FORCEPROP 2 LAST CDS_LIB mstr_standard
J 2
(1700 1900);
DISPLAY 0.787234 (1700 1900);
PAINT MONO (1700 1900);
DISPLAY INVISIBLE (1700 1900);
FORCEPROP 1 LAST BODY_TYPE PLUMBING
J 2
(1700 1850);
DISPLAY 1.234043 (1700 1850);
PAINT GREEN (1700 1850);
DISPLAY INVISIBLE (1700 1850);
FORCEPROP 1 LAST HDL_TAP TRUE
J 2
(1375 1775);
DISPLAY 1.234043 (1375 1775);
PAINT GREEN (1375 1775);
DISPLAY INVISIBLE (1375 1775);
FORCEPROP 1 LAST PATH I153
J 2
(1702 1900);
DISPLAY 0.872340 (1702 1900);
PAINT GREEN (1702 1900);
DISPLAY INVISIBLE (1702 1900);
FORCEADD TAP..6
R 2
(1700 1600);
FORCEPROP 3 LASTPIN (1650 1600) SIG_NAME M_D_DQ<0>
J 0
(1660 1610);
DISPLAY 0.659574 (1660 1610);
PAINT MONO (1660 1610);
DISPLAY INVISIBLE (1660 1610);
FORCEPROP 1 LASTPIN (1650 1600) BN 0
J 2
(1700 1610);
DISPLAY 0.617021 (1700 1610);
PAINT PINK (1700 1610);
FORCEPROP 2 LAST CDS_LIB mstr_standard
J 2
(1700 1600);
DISPLAY 0.787234 (1700 1600);
PAINT MONO (1700 1600);
DISPLAY INVISIBLE (1700 1600);
FORCEPROP 1 LAST BODY_TYPE PLUMBING
J 2
(1700 1550);
DISPLAY 1.234043 (1700 1550);
PAINT GREEN (1700 1550);
DISPLAY INVISIBLE (1700 1550);
FORCEPROP 1 LAST HDL_TAP TRUE
J 2
(1375 1475);
DISPLAY 1.234043 (1375 1475);
PAINT GREEN (1375 1475);
DISPLAY INVISIBLE (1375 1475);
FORCEPROP 1 LAST PATH I154
J 2
(1702 1600);
DISPLAY 0.872340 (1702 1600);
PAINT GREEN (1702 1600);
DISPLAY INVISIBLE (1702 1600);
FORCEADD TAP..6
R 2
(1700 1700);
FORCEPROP 3 LASTPIN (1650 1700) SIG_NAME M_D_DQ<2>
J 0
(1660 1710);
DISPLAY 0.659574 (1660 1710);
PAINT MONO (1660 1710);
DISPLAY INVISIBLE (1660 1710);
FORCEPROP 1 LASTPIN (1650 1700) BN 2
J 2
(1700 1710);
DISPLAY 0.617021 (1700 1710);
PAINT PINK (1700 1710);
FORCEPROP 2 LAST CDS_LIB mstr_standard
J 2
(1700 1700);
DISPLAY 0.787234 (1700 1700);
PAINT MONO (1700 1700);
DISPLAY INVISIBLE (1700 1700);
FORCEPROP 1 LAST BODY_TYPE PLUMBING
J 2
(1700 1650);
DISPLAY 1.234043 (1700 1650);
PAINT GREEN (1700 1650);
DISPLAY INVISIBLE (1700 1650);
FORCEPROP 1 LAST HDL_TAP TRUE
J 2
(1375 1575);
DISPLAY 1.234043 (1375 1575);
PAINT GREEN (1375 1575);
DISPLAY INVISIBLE (1375 1575);
FORCEPROP 1 LAST PATH I155
J 2
(1702 1700);
DISPLAY 0.872340 (1702 1700);
PAINT GREEN (1702 1700);
DISPLAY INVISIBLE (1702 1700);
FORCEADD TAP..6
R 2
(1700 1650);
FORCEPROP 3 LASTPIN (1650 1650) SIG_NAME M_D_DQ<1>
J 0
(1660 1660);
DISPLAY 0.659574 (1660 1660);
PAINT MONO (1660 1660);
DISPLAY INVISIBLE (1660 1660);
FORCEPROP 1 LASTPIN (1650 1650) BN 1
J 2
(1700 1660);
DISPLAY 0.617021 (1700 1660);
PAINT PINK (1700 1660);
FORCEPROP 2 LAST CDS_LIB mstr_standard
J 2
(1700 1650);
DISPLAY 0.787234 (1700 1650);
PAINT MONO (1700 1650);
DISPLAY INVISIBLE (1700 1650);
FORCEPROP 1 LAST BODY_TYPE PLUMBING
J 2
(1700 1600);
DISPLAY 1.234043 (1700 1600);
PAINT GREEN (1700 1600);
DISPLAY INVISIBLE (1700 1600);
FORCEPROP 1 LAST HDL_TAP TRUE
J 2
(1375 1525);
DISPLAY 1.234043 (1375 1525);
PAINT GREEN (1375 1525);
DISPLAY INVISIBLE (1375 1525);
FORCEPROP 1 LAST PATH I156
J 2
(1702 1650);
DISPLAY 0.872340 (1702 1650);
PAINT GREEN (1702 1650);
DISPLAY INVISIBLE (1702 1650);
FORCEADD TAP..6
R 2
(1700 1750);
FORCEPROP 3 LASTPIN (1650 1750) SIG_NAME M_D_DQ<3>
J 0
(1660 1760);
DISPLAY 0.659574 (1660 1760);
PAINT MONO (1660 1760);
DISPLAY INVISIBLE (1660 1760);
FORCEPROP 1 LASTPIN (1650 1750) BN 3
J 2
(1700 1760);
DISPLAY 0.617021 (1700 1760);
PAINT PINK (1700 1760);
FORCEPROP 2 LAST CDS_LIB mstr_standard
J 2
(1700 1750);
DISPLAY 0.787234 (1700 1750);
PAINT MONO (1700 1750);
DISPLAY INVISIBLE (1700 1750);
FORCEPROP 1 LAST BODY_TYPE PLUMBING
J 2
(1700 1700);
DISPLAY 1.234043 (1700 1700);
PAINT GREEN (1700 1700);
DISPLAY INVISIBLE (1700 1700);
FORCEPROP 1 LAST HDL_TAP TRUE
J 2
(1375 1625);
DISPLAY 1.234043 (1375 1625);
PAINT GREEN (1375 1625);
DISPLAY INVISIBLE (1375 1625);
FORCEPROP 1 LAST PATH I157
J 2
(1702 1750);
DISPLAY 0.872340 (1702 1750);
PAINT GREEN (1702 1750);
DISPLAY INVISIBLE (1702 1750);
FORCEADD SCONN288_H44441003..1
(950 3100);
FORCEPROP 1 LAST LOCATION J6M1
J 0
(500 5000);
DISPLAY 0.617021 (500 5000);
PAINT AQUA (500 5000);
FORCEPROP 1 LAST PART_NUMBER H44441-003
J 0
(500 1100);
DISPLAY 0.617021 (500 1100);
PAINT BLUE (500 1100);
FORCEPROP 1 LAST MATERIAL SCONN
J 0
(500 4950);
DISPLAY 0.617021 (500 4950);
PAINT SKYBLUE (500 4950);
FORCEPROP 2 LASTPIN (450 1600) $PN 146
J 2
(440 1610);
DISPLAY 0.617021 (440 1610);
PAINT ORANGE (440 1610);
FORCEPROP 2 LASTPIN (450 1950) $PN 284
J 2
(440 1960);
DISPLAY 0.617021 (440 1960);
PAINT ORANGE (440 1960);
FORCEPROP 2 LASTPIN (450 1750) $PN 285
J 2
(440 1760);
DISPLAY 0.617021 (440 1760);
PAINT ORANGE (440 1760);
FORCEPROP 2 LASTPIN (450 1700) $PN 141
J 2
(440 1710);
DISPLAY 0.617021 (440 1710);
PAINT ORANGE (440 1710);
FORCEPROP 2 LASTPIN (450 1300) $PN 230
J 2
(440 1310);
DISPLAY 0.617021 (440 1310);
PAINT ORANGE (440 1310);
FORCEPROP 2 LASTPIN (450 1900) $PN 238
J 2
(440 1910);
DISPLAY 0.617021 (440 1910);
PAINT ORANGE (440 1910);
FORCEPROP 2 LASTPIN (450 1850) $PN 140
J 2
(440 1860);
DISPLAY 0.617021 (440 1860);
PAINT ORANGE (440 1860);
FORCEPROP 2 LASTPIN (450 1800) $PN 139
J 2
(440 1810);
DISPLAY 0.617021 (440 1810);
PAINT ORANGE (440 1810);
FORCEPROP 2 LASTPIN (450 3250) $PN 237
J 2
(440 3260);
DISPLAY 0.617021 (440 3260);
PAINT ORANGE (440 3260);
FORCEPROP 2 LASTPIN (450 3200) $PN 93
J 2
(440 3210);
DISPLAY 0.617021 (440 3210);
PAINT ORANGE (440 3210);
FORCEPROP 2 LASTPIN (450 3150) $PN 89
J 2
(440 3160);
DISPLAY 0.617021 (440 3160);
PAINT ORANGE (440 3160);
FORCEPROP 2 LASTPIN (450 3100) $PN 84
J 2
(440 3110);
DISPLAY 0.617021 (440 3110);
PAINT ORANGE (440 3110);
FORCEPROP 2 LASTPIN (450 1500) $PN 144
J 2
(440 1510);
DISPLAY 0.617021 (440 1510);
PAINT ORANGE (440 1510);
FORCEPROP 2 LASTPIN (450 1450) $PN 227
J 2
(440 1460);
DISPLAY 0.617021 (440 1460);
PAINT ORANGE (440 1460);
FORCEPROP 2 LASTPIN (450 1400) $PN 205
J 2
(440 1410);
DISPLAY 0.617021 (440 1410);
PAINT ORANGE (440 1410);
FORCEPROP 2 LASTPIN (450 2200) $PN 58
J 2
(440 2210);
DISPLAY 0.617021 (440 2210);
PAINT ORANGE (440 2210);
FORCEPROP 2 LASTPIN (450 2250) $PN 222
J 2
(440 2260);
DISPLAY 0.617021 (440 2260);
PAINT ORANGE (440 2260);
FORCEPROP 2 LASTPIN (450 2850) $PN 91
J 2
(440 2860);
DISPLAY 0.617021 (440 2860);
PAINT ORANGE (440 2860);
FORCEPROP 2 LASTPIN (450 2800) $PN 87
J 2
(440 2810);
DISPLAY 0.617021 (440 2810);
PAINT ORANGE (440 2810);
FORCEPROP 2 LASTPIN (450 2150) $PN 78
J 2
(440 2160);
DISPLAY 0.617021 (440 2160);
PAINT ORANGE (440 2160);
FORCEPROP 2 LASTPIN (1450 4750) $PN 280
J 0
(1460 4760);
DISPLAY 0.617021 (1460 4760);
PAINT ORANGE (1460 4760);
FORCEPROP 2 LASTPIN (1450 4700) $PN 135
J 0
(1460 4710);
DISPLAY 0.617021 (1460 4710);
PAINT ORANGE (1460 4710);
FORCEPROP 2 LASTPIN (1450 4650) $PN 273
J 0
(1460 4660);
DISPLAY 0.617021 (1460 4660);
PAINT ORANGE (1460 4660);
FORCEPROP 2 LASTPIN (1450 4600) $PN 128
J 0
(1460 4610);
DISPLAY 0.617021 (1460 4610);
PAINT ORANGE (1460 4610);
FORCEPROP 2 LASTPIN (1450 4550) $PN 282
J 0
(1460 4560);
DISPLAY 0.617021 (1460 4560);
PAINT ORANGE (1460 4560);
FORCEPROP 2 LASTPIN (1450 4500) $PN 137
J 0
(1460 4510);
DISPLAY 0.617021 (1460 4510);
PAINT ORANGE (1460 4510);
FORCEPROP 2 LASTPIN (1450 4450) $PN 275
J 0
(1460 4460);
DISPLAY 0.617021 (1460 4460);
PAINT ORANGE (1460 4460);
FORCEPROP 2 LASTPIN (1450 4400) $PN 130
J 0
(1460 4410);
DISPLAY 0.617021 (1460 4410);
PAINT ORANGE (1460 4410);
FORCEPROP 2 LASTPIN (1450 4350) $PN 269
J 0
(1460 4360);
DISPLAY 0.617021 (1460 4360);
PAINT ORANGE (1460 4360);
FORCEPROP 2 LASTPIN (1450 4300) $PN 124
J 0
(1460 4310);
DISPLAY 0.617021 (1460 4310);
PAINT ORANGE (1460 4310);
FORCEPROP 2 LASTPIN (1450 4250) $PN 262
J 0
(1460 4260);
DISPLAY 0.617021 (1460 4260);
PAINT ORANGE (1460 4260);
FORCEPROP 2 LASTPIN (1450 4200) $PN 117
J 0
(1460 4210);
DISPLAY 0.617021 (1460 4210);
PAINT ORANGE (1460 4210);
FORCEPROP 2 LASTPIN (1450 4150) $PN 271
J 0
(1460 4160);
DISPLAY 0.617021 (1460 4160);
PAINT ORANGE (1460 4160);
FORCEPROP 2 LASTPIN (1450 4100) $PN 126
J 0
(1460 4110);
DISPLAY 0.617021 (1460 4110);
PAINT ORANGE (1460 4110);
FORCEPROP 2 LASTPIN (1450 4050) $PN 264
J 0
(1460 4060);
DISPLAY 0.617021 (1460 4060);
PAINT ORANGE (1460 4060);
FORCEPROP 2 LASTPIN (1450 4000) $PN 119
J 0
(1460 4010);
DISPLAY 0.617021 (1460 4010);
PAINT ORANGE (1460 4010);
FORCEPROP 2 LASTPIN (1450 3950) $PN 258
J 0
(1460 3960);
DISPLAY 0.617021 (1460 3960);
PAINT ORANGE (1460 3960);
FORCEPROP 2 LASTPIN (1450 3900) $PN 113
J 0
(1460 3910);
DISPLAY 0.617021 (1460 3910);
PAINT ORANGE (1460 3910);
FORCEPROP 2 LASTPIN (1450 3850) $PN 251
J 0
(1460 3860);
DISPLAY 0.617021 (1460 3860);
PAINT ORANGE (1460 3860);
FORCEPROP 2 LASTPIN (1450 3800) $PN 106
J 0
(1460 3810);
DISPLAY 0.617021 (1460 3810);
PAINT ORANGE (1460 3810);
FORCEPROP 2 LASTPIN (1450 3750) $PN 260
J 0
(1460 3760);
DISPLAY 0.617021 (1460 3760);
PAINT ORANGE (1460 3760);
FORCEPROP 2 LASTPIN (1450 3700) $PN 115
J 0
(1460 3710);
DISPLAY 0.617021 (1460 3710);
PAINT ORANGE (1460 3710);
FORCEPROP 2 LASTPIN (1450 3650) $PN 253
J 0
(1460 3660);
DISPLAY 0.617021 (1460 3660);
PAINT ORANGE (1460 3660);
FORCEPROP 2 LASTPIN (1450 3600) $PN 108
J 0
(1460 3610);
DISPLAY 0.617021 (1460 3610);
PAINT ORANGE (1460 3610);
FORCEPROP 2 LASTPIN (1450 3550) $PN 247
J 0
(1460 3560);
DISPLAY 0.617021 (1460 3560);
PAINT ORANGE (1460 3560);
FORCEPROP 2 LASTPIN (1450 3500) $PN 102
J 0
(1460 3510);
DISPLAY 0.617021 (1460 3510);
PAINT ORANGE (1460 3510);
FORCEPROP 2 LASTPIN (1450 3450) $PN 240
J 0
(1460 3460);
DISPLAY 0.617021 (1460 3460);
PAINT ORANGE (1460 3460);
FORCEPROP 2 LASTPIN (1450 3400) $PN 95
J 0
(1460 3410);
DISPLAY 0.617021 (1460 3410);
PAINT ORANGE (1460 3410);
FORCEPROP 2 LASTPIN (1450 3350) $PN 249
J 0
(1460 3360);
DISPLAY 0.617021 (1460 3360);
PAINT ORANGE (1460 3360);
FORCEPROP 2 LASTPIN (1450 3300) $PN 104
J 0
(1460 3310);
DISPLAY 0.617021 (1460 3310);
PAINT ORANGE (1460 3310);
FORCEPROP 2 LASTPIN (1450 3250) $PN 242
J 0
(1460 3260);
DISPLAY 0.617021 (1460 3260);
PAINT ORANGE (1460 3260);
FORCEPROP 2 LASTPIN (1450 3200) $PN 97
J 0
(1460 3210);
DISPLAY 0.617021 (1460 3210);
PAINT ORANGE (1460 3210);
FORCEPROP 2 LASTPIN (1450 3150) $PN 188
J 0
(1460 3160);
DISPLAY 0.617021 (1460 3160);
PAINT ORANGE (1460 3160);
FORCEPROP 2 LASTPIN (1450 3100) $PN 43
J 0
(1460 3110);
DISPLAY 0.617021 (1460 3110);
PAINT ORANGE (1460 3110);
FORCEPROP 2 LASTPIN (1450 3050) $PN 181
J 0
(1460 3060);
DISPLAY 0.617021 (1460 3060);
PAINT ORANGE (1460 3060);
FORCEPROP 2 LASTPIN (1450 3000) $PN 36
J 0
(1460 3010);
DISPLAY 0.617021 (1460 3010);
PAINT ORANGE (1460 3010);
FORCEPROP 2 LASTPIN (1450 2950) $PN 190
J 0
(1460 2960);
DISPLAY 0.617021 (1460 2960);
PAINT ORANGE (1460 2960);
FORCEPROP 2 LASTPIN (1450 2900) $PN 45
J 0
(1460 2910);
DISPLAY 0.617021 (1460 2910);
PAINT ORANGE (1460 2910);
FORCEPROP 2 LASTPIN (1450 2850) $PN 183
J 0
(1460 2860);
DISPLAY 0.617021 (1460 2860);
PAINT ORANGE (1460 2860);
FORCEPROP 2 LASTPIN (1450 2800) $PN 38
J 0
(1460 2810);
DISPLAY 0.617021 (1460 2810);
PAINT ORANGE (1460 2810);
FORCEPROP 2 LASTPIN (1450 2750) $PN 177
J 0
(1460 2760);
DISPLAY 0.617021 (1460 2760);
PAINT ORANGE (1460 2760);
FORCEPROP 2 LASTPIN (1450 2700) $PN 32
J 0
(1460 2710);
DISPLAY 0.617021 (1460 2710);
PAINT ORANGE (1460 2710);
FORCEPROP 2 LASTPIN (1450 2650) $PN 170
J 0
(1460 2660);
DISPLAY 0.617021 (1460 2660);
PAINT ORANGE (1460 2660);
FORCEPROP 2 LASTPIN (1450 2600) $PN 25
J 0
(1460 2610);
DISPLAY 0.617021 (1460 2610);
PAINT ORANGE (1460 2610);
FORCEPROP 2 LASTPIN (1450 2550) $PN 179
J 0
(1460 2560);
DISPLAY 0.617021 (1460 2560);
PAINT ORANGE (1460 2560);
FORCEPROP 2 LASTPIN (1450 2500) $PN 34
J 0
(1460 2510);
DISPLAY 0.617021 (1460 2510);
PAINT ORANGE (1460 2510);
FORCEPROP 2 LASTPIN (1450 2450) $PN 172
J 0
(1460 2460);
DISPLAY 0.617021 (1460 2460);
PAINT ORANGE (1460 2460);
FORCEPROP 2 LASTPIN (1450 2400) $PN 27
J 0
(1460 2410);
DISPLAY 0.617021 (1460 2410);
PAINT ORANGE (1460 2410);
FORCEPROP 2 LASTPIN (1450 2350) $PN 166
J 0
(1460 2360);
DISPLAY 0.617021 (1460 2360);
PAINT ORANGE (1460 2360);
FORCEPROP 2 LASTPIN (1450 2300) $PN 21
J 0
(1460 2310);
DISPLAY 0.617021 (1460 2310);
PAINT ORANGE (1460 2310);
FORCEPROP 2 LASTPIN (1450 2250) $PN 159
J 0
(1460 2260);
DISPLAY 0.617021 (1460 2260);
PAINT ORANGE (1460 2260);
FORCEPROP 2 LASTPIN (1450 2200) $PN 14
J 0
(1460 2210);
DISPLAY 0.617021 (1460 2210);
PAINT ORANGE (1460 2210);
FORCEPROP 2 LASTPIN (1450 2150) $PN 168
J 0
(1460 2160);
DISPLAY 0.617021 (1460 2160);
PAINT ORANGE (1460 2160);
FORCEPROP 2 LASTPIN (1450 2100) $PN 23
J 0
(1460 2110);
DISPLAY 0.617021 (1460 2110);
PAINT ORANGE (1460 2110);
FORCEPROP 2 LASTPIN (1450 2050) $PN 161
J 0
(1460 2060);
DISPLAY 0.617021 (1460 2060);
PAINT ORANGE (1460 2060);
FORCEPROP 2 LASTPIN (1450 2000) $PN 16
J 0
(1460 2010);
DISPLAY 0.617021 (1460 2010);
PAINT ORANGE (1460 2010);
FORCEPROP 2 LASTPIN (1450 1950) $PN 155
J 0
(1460 1960);
DISPLAY 0.617021 (1460 1960);
PAINT ORANGE (1460 1960);
FORCEPROP 2 LASTPIN (1450 1900) $PN 10
J 0
(1460 1910);
DISPLAY 0.617021 (1460 1910);
PAINT ORANGE (1460 1910);
FORCEPROP 2 LASTPIN (1450 1850) $PN 148
J 0
(1460 1860);
DISPLAY 0.617021 (1460 1860);
PAINT ORANGE (1460 1860);
FORCEPROP 2 LASTPIN (1450 1800) $PN 3
J 0
(1460 1810);
DISPLAY 0.617021 (1460 1810);
PAINT ORANGE (1460 1810);
FORCEPROP 2 LASTPIN (1450 1750) $PN 157
J 0
(1460 1760);
DISPLAY 0.617021 (1460 1760);
PAINT ORANGE (1460 1760);
FORCEPROP 2 LASTPIN (1450 1700) $PN 12
J 0
(1460 1710);
DISPLAY 0.617021 (1460 1710);
PAINT ORANGE (1460 1710);
FORCEPROP 2 LASTPIN (1450 1650) $PN 150
J 0
(1460 1660);
DISPLAY 0.617021 (1460 1660);
PAINT ORANGE (1460 1660);
FORCEPROP 2 LASTPIN (1450 1600) $PN 5
J 0
(1460 1610);
DISPLAY 0.617021 (1460 1610);
PAINT ORANGE (1460 1610);
FORCEPROP 2 LASTPIN (450 3000) $PN 203
J 2
(440 3010);
DISPLAY 0.617021 (440 3010);
PAINT ORANGE (440 3010);
FORCEPROP 2 LASTPIN (450 2950) $PN 60
J 2
(440 2960);
DISPLAY 0.617021 (440 2960);
PAINT ORANGE (440 2960);
FORCEPROP 2 LASTPIN (450 3550) $PN 218
J 2
(440 3560);
DISPLAY 0.617021 (440 3560);
PAINT ORANGE (440 3560);
FORCEPROP 2 LASTPIN (450 3500) $PN 219
J 2
(440 3510);
DISPLAY 0.617021 (440 3510);
PAINT ORANGE (440 3510);
FORCEPROP 2 LASTPIN (450 3450) $PN 74
J 2
(440 3460);
DISPLAY 0.617021 (440 3460);
PAINT ORANGE (440 3460);
FORCEPROP 2 LASTPIN (450 3400) $PN 75
J 2
(440 3410);
DISPLAY 0.617021 (440 3410);
PAINT ORANGE (440 3410);
FORCEPROP 2 LASTPIN (450 2700) $PN 199
J 2
(440 2710);
DISPLAY 0.617021 (440 2710);
PAINT ORANGE (440 2710);
FORCEPROP 2 LASTPIN (450 2650) $PN 54
J 2
(440 2660);
DISPLAY 0.617021 (440 2660);
PAINT ORANGE (440 2660);
FORCEPROP 2 LASTPIN (450 2600) $PN 192
J 2
(440 2610);
DISPLAY 0.617021 (440 2610);
PAINT ORANGE (440 2610);
FORCEPROP 2 LASTPIN (450 2550) $PN 47
J 2
(440 2560);
DISPLAY 0.617021 (440 2560);
PAINT ORANGE (440 2560);
FORCEPROP 2 LASTPIN (450 2500) $PN 201
J 2
(440 2510);
DISPLAY 0.617021 (440 2510);
PAINT ORANGE (440 2510);
FORCEPROP 2 LASTPIN (450 2450) $PN 56
J 2
(440 2460);
DISPLAY 0.617021 (440 2460);
PAINT ORANGE (440 2460);
FORCEPROP 2 LASTPIN (450 2400) $PN 194
J 2
(440 2410);
DISPLAY 0.617021 (440 2410);
PAINT ORANGE (440 2410);
FORCEPROP 2 LASTPIN (450 2350) $PN 49
J 2
(440 2360);
DISPLAY 0.617021 (440 2360);
PAINT ORANGE (440 2360);
FORCEPROP 2 LASTPIN (450 3300) $PN 235
J 2
(440 3310);
DISPLAY 0.617021 (440 3310);
PAINT ORANGE (440 3310);
FORCEPROP 2 LASTPIN (450 3700) $PN 207
J 2
(440 3710);
DISPLAY 0.617021 (440 3710);
PAINT ORANGE (440 3710);
FORCEPROP 2 LASTPIN (450 3650) $PN 63
J 2
(440 3660);
DISPLAY 0.617021 (440 3660);
PAINT ORANGE (440 3660);
FORCEPROP 2 LASTPIN (450 3800) $PN 224
J 2
(440 3810);
DISPLAY 0.617021 (440 3810);
PAINT ORANGE (440 3810);
FORCEPROP 2 LASTPIN (450 3750) $PN 81
J 2
(440 3760);
DISPLAY 0.617021 (440 3760);
PAINT ORANGE (440 3760);
FORCEPROP 2 LASTPIN (450 2100) $PN 208
J 2
(440 2110);
DISPLAY 0.617021 (440 2110);
PAINT ORANGE (440 2110);
FORCEPROP 2 LASTPIN (450 2050) $PN 62
J 2
(440 2060);
DISPLAY 0.617021 (440 2060);
PAINT ORANGE (440 2060);
FORCEPROP 2 LASTPIN (450 4750) $PN 234
J 2
(440 4760);
DISPLAY 0.617021 (440 4760);
PAINT ORANGE (440 4760);
FORCEPROP 2 LASTPIN (450 4700) $PN 82
J 2
(440 4710);
DISPLAY 0.617021 (440 4710);
PAINT ORANGE (440 4710);
FORCEPROP 2 LASTPIN (450 4650) $PN 86
J 2
(440 4660);
DISPLAY 0.617021 (440 4660);
PAINT ORANGE (440 4660);
FORCEPROP 2 LASTPIN (450 4600) $PN 228
J 2
(440 4610);
DISPLAY 0.617021 (440 4610);
PAINT ORANGE (440 4610);
FORCEPROP 2 LASTPIN (450 4550) $PN 232
J 2
(440 4560);
DISPLAY 0.617021 (440 4560);
PAINT ORANGE (440 4560);
FORCEPROP 2 LASTPIN (450 4500) $PN 65
J 2
(440 4510);
DISPLAY 0.617021 (440 4510);
PAINT ORANGE (440 4510);
FORCEPROP 2 LASTPIN (450 4450) $PN 210
J 2
(440 4460);
DISPLAY 0.617021 (440 4460);
PAINT ORANGE (440 4460);
FORCEPROP 2 LASTPIN (450 4400) $PN 225
J 2
(440 4410);
DISPLAY 0.617021 (440 4410);
PAINT ORANGE (440 4410);
FORCEPROP 2 LASTPIN (450 4350) $PN 66
J 2
(440 4360);
DISPLAY 0.617021 (440 4360);
PAINT ORANGE (440 4360);
FORCEPROP 2 LASTPIN (450 4300) $PN 68
J 2
(440 4310);
DISPLAY 0.617021 (440 4310);
PAINT ORANGE (440 4310);
FORCEPROP 2 LASTPIN (450 4250) $PN 211
J 2
(440 4260);
DISPLAY 0.617021 (440 4260);
PAINT ORANGE (440 4260);
FORCEPROP 2 LASTPIN (450 4200) $PN 69
J 2
(440 4210);
DISPLAY 0.617021 (440 4210);
PAINT ORANGE (440 4210);
FORCEPROP 2 LASTPIN (450 4150) $PN 213
J 2
(440 4160);
DISPLAY 0.617021 (440 4160);
PAINT ORANGE (440 4160);
FORCEPROP 2 LASTPIN (450 4100) $PN 214
J 2
(440 4110);
DISPLAY 0.617021 (440 4110);
PAINT ORANGE (440 4110);
FORCEPROP 2 LASTPIN (450 4050) $PN 71
J 2
(440 4060);
DISPLAY 0.617021 (440 4060);
PAINT ORANGE (440 4060);
FORCEPROP 2 LASTPIN (450 4000) $PN 216
J 2
(440 4010);
DISPLAY 0.617021 (440 4010);
PAINT ORANGE (440 4010);
FORCEPROP 2 LASTPIN (450 3950) $PN 72
J 2
(440 3960);
DISPLAY 0.617021 (440 3960);
PAINT ORANGE (440 3960);
FORCEPROP 2 LASTPIN (450 3900) $PN 79
J 2
(440 3910);
DISPLAY 0.617021 (440 3910);
PAINT ORANGE (440 3910);
FORCEPROP 1 LAST PACK_TYPE PIP
J 0
(500 5050);
PAINT SKYBLUE (500 5050);
DISPLAY INVISIBLE (500 5050);
FORCEPROP 2 LAST BOM_COST MEM
J 0
(1000 2450);
PAINT ORANGE (1000 2450);
DISPLAY INVISIBLE (1000 2450);
FORCEPROP 2 LAST CDS_LIB mstr_sconn
J 0
(950 3100);
PAINT ORANGE (950 3100);
DISPLAY INVISIBLE (950 3100);
FORCEPROP 2 LAST SEC_TYPE PIP
J 0
(500 5050);
DISPLAY 1.021277 (500 5050);
PAINT ORANGE (500 5050);
DISPLAY INVISIBLE (500 5050);
FORCEPROP 2 LAST SEC 1
J 0
(500 5050);
DISPLAY 0.680851 (500 5050);
PAINT MONO (500 5050);
DISPLAY INVISIBLE (500 5050);
FORCEPROP 2 LAST CDS_LOCATION J6M1
J 0
(500 5000);
DISPLAY 0.617021 (500 5000);
PAINT AQUA (500 5000);
DISPLAY INVISIBLE (500 5000);
FORCEPROP 1 LAST PATH I158
J 0
(950 4950);
PAINT GREEN (950 4950);
DISPLAY INVISIBLE (950 4950);
FORCEPROP 2 LAST ROOM DDR4_CH_D
J 0
(1000 2450);
PAINT ORANGE (1000 2450);
DISPLAY INVISIBLE (1000 2450);
FORCEADD OFFPAGE..1
(-550 3850);
FORCEPROP 2 LAST $XR0 26 
J 0
(-771 3850);
DISPLAY 0.638298 (-771 3850);
PAINT MONO (-771 3850);
FORCEPROP 2 LAST $XR1 49 
J 0
(-861 3850);
DISPLAY 0.638298 (-861 3850);
PAINT MONO (-861 3850);
FORCEPROP 2 LAST CDS_LIB mstr_standard
J 0
(-550 3850);
DISPLAY 0.787234 (-550 3850);
PAINT MONO (-550 3850);
DISPLAY INVISIBLE (-550 3850);
FORCEPROP 1 LAST OFFPAGE TRUE
J 0
(-225 3725);
DISPLAY 0.936170 (-225 3725);
PAINT GREEN (-225 3725);
DISPLAY INVISIBLE (-225 3725);
FORCEPROP 1 LAST COMMENT_BODY TRUE
J 0
(-425 3750);
DISPLAY 0.936170 (-425 3750);
PAINT GREEN (-425 3750);
DISPLAY INVISIBLE (-425 3750);
FORCEPROP 2 LAST PATH I159
J 0
(-750 3900);
DISPLAY 1.021277 (-750 3900);
PAINT ORANGE (-750 3900);
DISPLAY INVISIBLE (-750 3900);
FORCEADD TAP..6
R 2
(4100 4300);
FORCEPROP 3 LASTPIN (4050 4300) SIG_NAME M_D_DQS_DP<12>
J 0
(4060 4310);
DISPLAY 0.659574 (4060 4310);
PAINT MONO (4060 4310);
DISPLAY INVISIBLE (4060 4310);
FORCEPROP 1 LASTPIN (4050 4300) BN 12
J 2
(4100 4310);
DISPLAY 0.617021 (4100 4310);
PAINT PINK (4100 4310);
FORCEPROP 2 LAST CDS_LIB mstr_standard
J 0
(4100 4300);
DISPLAY 0.787234 (4100 4300);
PAINT MONO (4100 4300);
DISPLAY INVISIBLE (4100 4300);
FORCEPROP 1 LAST BODY_TYPE PLUMBING
J 2
(4100 4250);
DISPLAY 1.234043 (4100 4250);
PAINT GREEN (4100 4250);
DISPLAY INVISIBLE (4100 4250);
FORCEPROP 1 LAST HDL_TAP TRUE
J 2
(3775 4175);
DISPLAY 1.234043 (3775 4175);
PAINT GREEN (3775 4175);
DISPLAY INVISIBLE (3775 4175);
FORCEPROP 1 LAST PATH I16
J 2
(4102 4300);
DISPLAY 0.872340 (4102 4300);
PAINT GREEN (4102 4300);
DISPLAY INVISIBLE (4102 4300);
FORCEADD OFFPAGE..1
(-550 3600);
FORCEPROP 2 LAST $XR0 26 
J 0
(-771 3600);
DISPLAY 0.638298 (-771 3600);
PAINT MONO (-771 3600);
FORCEPROP 2 LAST $XR1 49 
J 0
(-861 3600);
DISPLAY 0.638298 (-861 3600);
PAINT MONO (-861 3600);
FORCEPROP 2 LAST CDS_LIB mstr_standard
J 0
(-550 3600);
DISPLAY 0.787234 (-550 3600);
PAINT MONO (-550 3600);
DISPLAY INVISIBLE (-550 3600);
FORCEPROP 1 LAST OFFPAGE TRUE
J 0
(-225 3475);
DISPLAY 0.936170 (-225 3475);
PAINT GREEN (-225 3475);
DISPLAY INVISIBLE (-225 3475);
FORCEPROP 1 LAST COMMENT_BODY TRUE
J 0
(-425 3500);
DISPLAY 0.936170 (-425 3500);
PAINT GREEN (-425 3500);
DISPLAY INVISIBLE (-425 3500);
FORCEPROP 2 LAST PATH I160
J 0
(-750 3650);
DISPLAY 1.021277 (-750 3650);
PAINT ORANGE (-750 3650);
DISPLAY INVISIBLE (-750 3650);
FORCEADD OFFPAGE..1
(-550 3750);
FORCEPROP 2 LAST $XR0 26 
J 0
(-771 3750);
DISPLAY 0.638298 (-771 3750);
PAINT MONO (-771 3750);
FORCEPROP 2 LAST $XR1 49 
J 0
(-861 3750);
DISPLAY 0.638298 (-861 3750);
PAINT MONO (-861 3750);
FORCEPROP 2 LAST CDS_LIB mstr_standard
J 0
(-550 3750);
DISPLAY 0.787234 (-550 3750);
PAINT MONO (-550 3750);
DISPLAY INVISIBLE (-550 3750);
FORCEPROP 1 LAST OFFPAGE TRUE
J 0
(-225 3625);
DISPLAY 0.936170 (-225 3625);
PAINT GREEN (-225 3625);
DISPLAY INVISIBLE (-225 3625);
FORCEPROP 1 LAST COMMENT_BODY TRUE
J 0
(-425 3650);
DISPLAY 0.936170 (-425 3650);
PAINT GREEN (-425 3650);
DISPLAY INVISIBLE (-425 3650);
FORCEPROP 2 LAST PATH I161
J 0
(-750 3800);
DISPLAY 1.021277 (-750 3800);
PAINT ORANGE (-750 3800);
DISPLAY INVISIBLE (-750 3800);
FORCEADD OFFPAGE..1
(-550 3550);
FORCEPROP 2 LAST $XR0 26 
J 0
(-771 3550);
DISPLAY 0.638298 (-771 3550);
PAINT MONO (-771 3550);
FORCEPROP 2 LAST $XR1 49 
J 0
(-861 3550);
DISPLAY 0.638298 (-861 3550);
PAINT MONO (-861 3550);
FORCEPROP 2 LAST CDS_LIB mstr_standard
J 0
(-550 3550);
DISPLAY 0.787234 (-550 3550);
PAINT MONO (-550 3550);
DISPLAY INVISIBLE (-550 3550);
FORCEPROP 1 LAST OFFPAGE TRUE
J 0
(-225 3425);
DISPLAY 0.936170 (-225 3425);
PAINT GREEN (-225 3425);
DISPLAY INVISIBLE (-225 3425);
FORCEPROP 1 LAST COMMENT_BODY TRUE
J 0
(-425 3450);
DISPLAY 0.936170 (-425 3450);
PAINT GREEN (-425 3450);
DISPLAY INVISIBLE (-425 3450);
FORCEPROP 2 LAST PATH I162
J 0
(-750 3600);
DISPLAY 1.021277 (-750 3600);
PAINT ORANGE (-750 3600);
DISPLAY INVISIBLE (-750 3600);
FORCEADD OFFPAGE..1
(-550 3350);
FORCEPROP 2 LAST $XR0 26 
J 0
(-771 3350);
DISPLAY 0.638298 (-771 3350);
PAINT MONO (-771 3350);
FORCEPROP 2 LAST $XR1 49 
J 0
(-861 3350);
DISPLAY 0.638298 (-861 3350);
PAINT MONO (-861 3350);
FORCEPROP 2 LAST CDS_LIB mstr_standard
J 0
(-550 3350);
DISPLAY 0.787234 (-550 3350);
PAINT MONO (-550 3350);
DISPLAY INVISIBLE (-550 3350);
FORCEPROP 1 LAST OFFPAGE TRUE
J 0
(-225 3225);
DISPLAY 0.936170 (-225 3225);
PAINT GREEN (-225 3225);
DISPLAY INVISIBLE (-225 3225);
FORCEPROP 1 LAST COMMENT_BODY TRUE
J 0
(-425 3250);
DISPLAY 0.936170 (-425 3250);
PAINT GREEN (-425 3250);
DISPLAY INVISIBLE (-425 3250);
FORCEPROP 2 LAST PATH I163
J 0
(-750 3400);
DISPLAY 1.021277 (-750 3400);
PAINT ORANGE (-750 3400);
DISPLAY INVISIBLE (-750 3400);
FORCEADD OFFPAGE..1
(-550 3300);
FORCEPROP 2 LAST $XR0 26 
J 0
(-771 3300);
DISPLAY 0.638298 (-771 3300);
PAINT MONO (-771 3300);
FORCEPROP 2 LAST $XR1 49 
J 0
(-861 3300);
DISPLAY 0.638298 (-861 3300);
PAINT MONO (-861 3300);
FORCEPROP 2 LAST CDS_LIB mstr_standard
J 0
(-550 3300);
DISPLAY 0.787234 (-550 3300);
PAINT MONO (-550 3300);
DISPLAY INVISIBLE (-550 3300);
FORCEPROP 1 LAST OFFPAGE TRUE
J 0
(-225 3175);
DISPLAY 0.936170 (-225 3175);
PAINT GREEN (-225 3175);
DISPLAY INVISIBLE (-225 3175);
FORCEPROP 1 LAST COMMENT_BODY TRUE
J 0
(-425 3200);
DISPLAY 0.936170 (-425 3200);
PAINT GREEN (-425 3200);
DISPLAY INVISIBLE (-425 3200);
FORCEPROP 2 LAST PATH I164
J 0
(-750 3350);
DISPLAY 1.021277 (-750 3350);
PAINT ORANGE (-750 3350);
DISPLAY INVISIBLE (-750 3350);
FORCEADD OFFPAGE..1
(-550 3050);
FORCEPROP 2 LAST $XR0 26 
J 0
(-771 3050);
DISPLAY 0.638298 (-771 3050);
PAINT MONO (-771 3050);
FORCEPROP 2 LAST $XR1 49 
J 0
(-861 3050);
DISPLAY 0.638298 (-861 3050);
PAINT MONO (-861 3050);
FORCEPROP 2 LAST CDS_LIB mstr_standard
J 0
(-550 3050);
DISPLAY 0.787234 (-550 3050);
PAINT MONO (-550 3050);
DISPLAY INVISIBLE (-550 3050);
FORCEPROP 1 LAST OFFPAGE TRUE
J 0
(-225 2925);
DISPLAY 0.936170 (-225 2925);
PAINT GREEN (-225 2925);
DISPLAY INVISIBLE (-225 2925);
FORCEPROP 1 LAST COMMENT_BODY TRUE
J 0
(-425 2950);
DISPLAY 0.936170 (-425 2950);
PAINT GREEN (-425 2950);
DISPLAY INVISIBLE (-425 2950);
FORCEPROP 2 LAST PATH I165
J 0
(-750 3100);
DISPLAY 1.021277 (-750 3100);
PAINT ORANGE (-750 3100);
DISPLAY INVISIBLE (-750 3100);
FORCEADD OFFPAGE..1
(-550 2900);
FORCEPROP 2 LAST $XR0 26 
J 0
(-771 2900);
DISPLAY 0.638298 (-771 2900);
PAINT MONO (-771 2900);
FORCEPROP 2 LAST $XR1 49 
J 0
(-861 2900);
DISPLAY 0.638298 (-861 2900);
PAINT MONO (-861 2900);
FORCEPROP 2 LAST CDS_LIB mstr_standard
J 0
(-550 2900);
DISPLAY 0.787234 (-550 2900);
PAINT MONO (-550 2900);
DISPLAY INVISIBLE (-550 2900);
FORCEPROP 1 LAST OFFPAGE TRUE
J 0
(-225 2775);
DISPLAY 0.936170 (-225 2775);
PAINT GREEN (-225 2775);
DISPLAY INVISIBLE (-225 2775);
FORCEPROP 1 LAST COMMENT_BODY TRUE
J 0
(-425 2800);
DISPLAY 0.936170 (-425 2800);
PAINT GREEN (-425 2800);
DISPLAY INVISIBLE (-425 2800);
FORCEPROP 2 LAST PATH I166
J 0
(-750 2950);
DISPLAY 1.021277 (-750 2950);
PAINT ORANGE (-750 2950);
DISPLAY INVISIBLE (-750 2950);
FORCEADD OFFPAGE..1
(-550 2700);
FORCEPROP 2 LAST $XR0 26 
J 0
(-801 2700);
DISPLAY 0.638298 (-801 2700);
PAINT MONO (-801 2700);
FORCEPROP 2 LAST $XR1 49 
J 0
(-891 2700);
DISPLAY 0.638298 (-891 2700);
PAINT MONO (-891 2700);
FORCEPROP 2 LAST CDS_LIB mstr_standard
J 0
(-550 2700);
DISPLAY 0.787234 (-550 2700);
PAINT MONO (-550 2700);
DISPLAY INVISIBLE (-550 2700);
FORCEPROP 1 LAST OFFPAGE TRUE
J 0
(-225 2575);
DISPLAY 0.936170 (-225 2575);
PAINT GREEN (-225 2575);
DISPLAY INVISIBLE (-225 2575);
FORCEPROP 1 LAST COMMENT_BODY TRUE
J 0
(-425 2600);
DISPLAY 0.936170 (-425 2600);
PAINT GREEN (-425 2600);
DISPLAY INVISIBLE (-425 2600);
FORCEPROP 2 LAST PATH I167
J 0
(-800 2750);
DISPLAY 1.021277 (-800 2750);
PAINT ORANGE (-800 2750);
DISPLAY INVISIBLE (-800 2750);
FORCEADD OFFPAGE..6
(-550 2750);
FORCEPROP 2 LAST $XR0 26 
J 0
(-799 2750);
DISPLAY 0.638298 (-799 2750);
PAINT MONO (-799 2750);
FORCEPROP 2 LAST $XR1 49 
J 0
(-889 2750);
DISPLAY 0.638298 (-889 2750);
PAINT MONO (-889 2750);
FORCEPROP 2 LAST CDS_LIB mstr_standard
J 0
(-550 2750);
DISPLAY 0.787234 (-550 2750);
PAINT MONO (-550 2750);
DISPLAY INVISIBLE (-550 2750);
FORCEPROP 1 LAST OFFPAGE TRUE
J 0
(-225 2625);
DISPLAY 0.936170 (-225 2625);
PAINT GREEN (-225 2625);
DISPLAY INVISIBLE (-225 2625);
FORCEPROP 1 LAST COMMENT_BODY TRUE
J 0
(-450 2675);
DISPLAY 0.936170 (-450 2675);
PAINT GREEN (-450 2675);
DISPLAY INVISIBLE (-450 2675);
FORCEPROP 2 LAST PATH I168
J 0
(-775 2800);
DISPLAY 1.021277 (-775 2800);
PAINT ORANGE (-775 2800);
DISPLAY INVISIBLE (-775 2800);
FORCEADD OFFPAGE..1
(-550 2650);
FORCEPROP 2 LAST $XR0 21 
J 0
(-771 2650);
DISPLAY 0.638298 (-771 2650);
PAINT MONO (-771 2650);
FORCEPROP 2 LAST $XR1 49 
J 0
(-861 2650);
DISPLAY 0.638298 (-861 2650);
PAINT MONO (-861 2650);
FORCEPROP 2 LAST $XR2 51 
J 0
(-951 2650);
DISPLAY 0.638298 (-951 2650);
PAINT MONO (-951 2650);
FORCEPROP 2 LAST $XR3 52 
J 0
(-1041 2650);
DISPLAY 0.638298 (-1041 2650);
PAINT MONO (-1041 2650);
FORCEPROP 2 LAST $XR4 53 
J 0
(-1131 2650);
DISPLAY 0.638298 (-1131 2650);
PAINT MONO (-1131 2650);
FORCEPROP 2 LAST $XR5 54 
J 0
(-1221 2650);
DISPLAY 0.638298 (-1221 2650);
PAINT MONO (-1221 2650);
FORCEPROP 2 LAST CDS_LIB mstr_standard
J 0
(-550 2650);
DISPLAY 0.787234 (-550 2650);
PAINT MONO (-550 2650);
DISPLAY INVISIBLE (-550 2650);
FORCEPROP 1 LAST OFFPAGE TRUE
J 0
(-225 2525);
DISPLAY 0.936170 (-225 2525);
PAINT GREEN (-225 2525);
DISPLAY INVISIBLE (-225 2525);
FORCEPROP 1 LAST COMMENT_BODY TRUE
J 0
(-425 2550);
DISPLAY 0.936170 (-425 2550);
PAINT GREEN (-425 2550);
DISPLAY INVISIBLE (-425 2550);
FORCEPROP 2 LAST PATH I169
J 0
(-725 2700);
DISPLAY 1.021277 (-725 2700);
PAINT ORANGE (-725 2700);
DISPLAY INVISIBLE (-725 2700);
FORCEADD TAP..6
R 2
(4100 4200);
FORCEPROP 3 LASTPIN (4050 4200) SIG_NAME M_D_DQS_DP<11>
J 0
(4060 4210);
DISPLAY 0.659574 (4060 4210);
PAINT MONO (4060 4210);
DISPLAY INVISIBLE (4060 4210);
FORCEPROP 1 LASTPIN (4050 4200) BN 11
J 2
(4100 4210);
DISPLAY 0.617021 (4100 4210);
PAINT PINK (4100 4210);
FORCEPROP 2 LAST CDS_LIB mstr_standard
J 0
(4100 4200);
DISPLAY 0.787234 (4100 4200);
PAINT MONO (4100 4200);
DISPLAY INVISIBLE (4100 4200);
FORCEPROP 1 LAST BODY_TYPE PLUMBING
J 2
(4100 4150);
DISPLAY 1.234043 (4100 4150);
PAINT GREEN (4100 4150);
DISPLAY INVISIBLE (4100 4150);
FORCEPROP 1 LAST HDL_TAP TRUE
J 2
(3775 4075);
DISPLAY 1.234043 (3775 4075);
PAINT GREEN (3775 4075);
DISPLAY INVISIBLE (3775 4075);
FORCEPROP 1 LAST PATH I17
J 2
(4102 4200);
DISPLAY 0.872340 (4102 4200);
PAINT GREEN (4102 4200);
DISPLAY INVISIBLE (4102 4200);
FORCEADD OFFPAGE..5
(-575 2100);
FORCEPROP 2 LAST $XR0 49 
J 0
(-799 2100);
DISPLAY 0.638298 (-799 2100);
PAINT MONO (-799 2100);
FORCEPROP 2 LAST $XR1 26 
J 0
(-889 2100);
DISPLAY 0.638298 (-889 2100);
PAINT MONO (-889 2100);
FORCEPROP 2 LAST CDS_LIB mstr_standard
J 0
(-575 2100);
DISPLAY 0.787234 (-575 2100);
PAINT MONO (-575 2100);
DISPLAY INVISIBLE (-575 2100);
FORCEPROP 1 LAST OFFPAGE TRUE
J 0
(-250 1975);
DISPLAY 1.404255 (-250 1975);
PAINT GREEN (-250 1975);
DISPLAY INVISIBLE (-250 1975);
FORCEPROP 1 LAST COMMENT_BODY TRUE
J 0
(-475 2025);
DISPLAY 1.404255 (-475 2025);
PAINT GREEN (-475 2025);
DISPLAY INVISIBLE (-475 2025);
FORCEPROP 2 LAST PATH I170
J 0
(-775 2150);
DISPLAY 1.021277 (-775 2150);
PAINT ORANGE (-775 2150);
DISPLAY INVISIBLE (-775 2150);
FORCEADD OFFPAGE..5
(-775 2450);
FORCEPROP 2 LAST $XR0 43 
J 0
(-999 2450);
DISPLAY 0.638298 (-999 2450);
PAINT MONO (-999 2450);
FORCEPROP 2 LAST $XR1 44 
J 0
(-1089 2450);
DISPLAY 0.638298 (-1089 2450);
PAINT MONO (-1089 2450);
FORCEPROP 2 LAST $XR2 45 
J 0
(-1179 2450);
DISPLAY 0.638298 (-1179 2450);
PAINT MONO (-1179 2450);
FORCEPROP 2 LAST $XR3 46 
J 0
(-1269 2450);
DISPLAY 0.638298 (-1269 2450);
PAINT MONO (-1269 2450);
FORCEPROP 2 LAST $XR4 47 
J 0
(-1359 2450);
DISPLAY 0.638298 (-1359 2450);
PAINT MONO (-1359 2450);
FORCEPROP 2 LAST $XR5 48 
J 0
(-1449 2450);
DISPLAY 0.638298 (-1449 2450);
PAINT MONO (-1449 2450);
FORCEPROP 2 LAST $XR6 49 
J 0
(-1539 2450);
DISPLAY 0.638298 (-1539 2450);
PAINT MONO (-1539 2450);
FORCEPROP 2 LAST $XR7 51 
J 0
(-1629 2450);
DISPLAY 0.638298 (-1629 2450);
PAINT MONO (-1629 2450);
FORCEPROP 2 LAST $XR8 52 
J 0
(-1719 2450);
DISPLAY 0.638298 (-1719 2450);
PAINT MONO (-1719 2450);
FORCEPROP 2 LAST $XR9 53 
J 0
(-1809 2450);
DISPLAY 0.638298 (-1809 2450);
PAINT MONO (-1809 2450);
FORCEPROP 2 LAST $XR10 54 
J 0
(-999 2414);
DISPLAY 0.638298 (-999 2414);
PAINT MONO (-999 2414);
FORCEPROP 2 LAST $XR11 77 
J 0
(-1089 2414);
DISPLAY 0.638298 (-1089 2414);
PAINT MONO (-1089 2414);
FORCEPROP 2 LAST $XR12 78 
J 0
(-1179 2414);
DISPLAY 0.638298 (-1179 2414);
PAINT MONO (-1179 2414);
FORCEPROP 2 LAST $XR13 79 
J 0
(-1269 2414);
DISPLAY 0.638298 (-1269 2414);
PAINT MONO (-1269 2414);
FORCEPROP 2 LAST $XR14 80 
J 0
(-1359 2414);
DISPLAY 0.638298 (-1359 2414);
PAINT MONO (-1359 2414);
FORCEPROP 2 LAST $XR15 81 
J 0
(-1449 2414);
DISPLAY 0.638298 (-1449 2414);
PAINT MONO (-1449 2414);
FORCEPROP 2 LAST $XR16 82 
J 0
(-1539 2414);
DISPLAY 0.638298 (-1539 2414);
PAINT MONO (-1539 2414);
FORCEPROP 2 LAST $XR17 83 
J 0
(-1629 2414);
DISPLAY 0.638298 (-1629 2414);
PAINT MONO (-1629 2414);
FORCEPROP 2 LAST $XR18 84 
J 0
(-1719 2414);
DISPLAY 0.638298 (-1719 2414);
PAINT MONO (-1719 2414);
FORCEPROP 2 LAST $XR19 85 
J 0
(-1809 2414);
DISPLAY 0.638298 (-1809 2414);
PAINT MONO (-1809 2414);
FORCEPROP 2 LAST $XR20 86 
J 0
(-999 2486);
DISPLAY 0.638298 (-999 2486);
PAINT MONO (-999 2486);
FORCEPROP 2 LAST $XR21 87 
J 0
(-1089 2486);
DISPLAY 0.638298 (-1089 2486);
PAINT MONO (-1089 2486);
FORCEPROP 2 LAST $XR22 88 
J 0
(-1179 2486);
DISPLAY 0.638298 (-1179 2486);
PAINT MONO (-1179 2486);
FORCEPROP 2 LAST $XR23 94 
J 0
(-1269 2486);
DISPLAY 0.638298 (-1269 2486);
PAINT MONO (-1269 2486);
FORCEPROP 2 LAST CDS_LIB mstr_standard
J 0
(-775 2450);
DISPLAY 0.787234 (-775 2450);
PAINT MONO (-775 2450);
DISPLAY INVISIBLE (-775 2450);
FORCEPROP 1 LAST OFFPAGE TRUE
J 0
(-450 2325);
DISPLAY 1.404255 (-450 2325);
PAINT GREEN (-450 2325);
DISPLAY INVISIBLE (-450 2325);
FORCEPROP 1 LAST COMMENT_BODY TRUE
J 0
(-675 2375);
DISPLAY 1.404255 (-675 2375);
PAINT GREEN (-675 2375);
DISPLAY INVISIBLE (-675 2375);
FORCEPROP 2 LAST PATH I171
J 0
(-975 2525);
DISPLAY 1.021277 (-975 2525);
PAINT ORANGE (-975 2525);
DISPLAY INVISIBLE (-975 2525);
FORCEADD PVPP_DEF..1
(-1650 2100);
FORCEPROP 3 LASTPIN (-1650 2050) SIG_NAME PVPP_DEF\g
J 0
(-1640 2060);
DISPLAY 0.659574 (-1640 2060);
PAINT MONO (-1640 2060);
DISPLAY INVISIBLE (-1640 2060);
FORCEPROP 1 LAST VOLTAGE 2.5V
J 0
(-1695 2057);
DISPLAY 0.340426 (-1695 2057);
PAINT SKYBLUE (-1695 2057);
DISPLAY INVISIBLE (-1695 2057);
FORCEPROP 0 LAST BOM_COST MEM
J 0
(-1650 2200);
PAINT ORANGE (-1650 2200);
DISPLAY INVISIBLE (-1650 2200);
FORCEPROP 2 LAST CDS_LIB mstr_symbols
J 0
(-1650 2100);
PAINT ORANGE (-1650 2100);
DISPLAY INVISIBLE (-1650 2100);
FORCEPROP 1 LAST BODY_TYPE PLUMBING
J 0
(-1695 2057);
DISPLAY 0.340426 (-1695 2057);
PAINT GREEN (-1695 2057);
DISPLAY INVISIBLE (-1695 2057);
FORCEPROP 1 LAST PATH I172
J 0
(-1600 2125);
DISPLAY 0.872340 (-1600 2125);
PAINT AQUA (-1600 2125);
DISPLAY INVISIBLE (-1600 2125);
FORCEPROP 2 LAST ROOM DDR4_CH_B
J 0
(-1650 2200);
PAINT ORANGE (-1650 2200);
DISPLAY INVISIBLE (-1650 2200);
FORCEPROP 1 LAST HDL_POWER PVPP_DEF
J 1
(-1650 2150);
DISPLAY 0.872340 (-1650 2150);
PAINT GREEN (-1650 2150);
DISPLAY INVISIBLE (-1650 2150);
FORCEADD OFFPAGE..1
(-550 2050);
FORCEPROP 2 LAST $XR0 26 
J 0
(-801 2050);
DISPLAY 0.638298 (-801 2050);
PAINT MONO (-801 2050);
FORCEPROP 2 LAST $XR1 49 
J 0
(-891 2050);
DISPLAY 0.638298 (-891 2050);
PAINT MONO (-891 2050);
FORCEPROP 2 LAST CDS_LIB mstr_standard
J 0
(-550 2050);
DISPLAY 0.787234 (-550 2050);
PAINT MONO (-550 2050);
DISPLAY INVISIBLE (-550 2050);
FORCEPROP 1 LAST OFFPAGE TRUE
J 0
(-225 1925);
DISPLAY 0.936170 (-225 1925);
PAINT GREEN (-225 1925);
DISPLAY INVISIBLE (-225 1925);
FORCEPROP 1 LAST COMMENT_BODY TRUE
J 0
(-425 1950);
DISPLAY 0.936170 (-425 1950);
PAINT GREEN (-425 1950);
DISPLAY INVISIBLE (-425 1950);
FORCEPROP 2 LAST PATH I173
J 0
(-800 2100);
DISPLAY 1.021277 (-800 2100);
PAINT ORANGE (-800 2100);
DISPLAY INVISIBLE (-800 2100);
FORCEADD OFFPAGE..6
(-400 1750);
FORCEPROP 2 LAST $XR0 49 
J 0
(-649 1750);
DISPLAY 0.638298 (-649 1750);
PAINT MONO (-649 1750);
FORCEPROP 2 LAST $XR1 51 
J 0
(-739 1750);
DISPLAY 0.638298 (-739 1750);
PAINT MONO (-739 1750);
FORCEPROP 2 LAST $XR2 52 
J 0
(-829 1750);
DISPLAY 0.638298 (-829 1750);
PAINT MONO (-829 1750);
FORCEPROP 2 LAST $XR3 53 
J 0
(-919 1750);
DISPLAY 0.638298 (-919 1750);
PAINT MONO (-919 1750);
FORCEPROP 2 LAST $XR4 54 
J 0
(-1009 1750);
DISPLAY 0.638298 (-1009 1750);
PAINT MONO (-1009 1750);
FORCEPROP 2 LAST $XR5 99 
J 0
(-1099 1750);
DISPLAY 0.638298 (-1099 1750);
PAINT MONO (-1099 1750);
FORCEPROP 2 LASTPIN (-350 1750) SIG_NAME SMB_DDR_DEF_VPP_SDA
J 0
(-310 1760);
DISPLAY 0.617021 (-310 1760);
PAINT ORANGE (-310 1760);
FORCEPROP 2 LAST CDS_LIB mstr_standard
J 0
(-400 1750);
DISPLAY 0.787234 (-400 1750);
PAINT MONO (-400 1750);
DISPLAY INVISIBLE (-400 1750);
FORCEPROP 1 LAST OFFPAGE TRUE
J 0
(-75 1625);
DISPLAY 0.936170 (-75 1625);
PAINT GREEN (-75 1625);
DISPLAY INVISIBLE (-75 1625);
FORCEPROP 1 LAST COMMENT_BODY TRUE
J 0
(-300 1675);
DISPLAY 0.936170 (-300 1675);
PAINT GREEN (-300 1675);
DISPLAY INVISIBLE (-300 1675);
FORCEPROP 2 LAST PATH I174
J 0
(-625 1800);
DISPLAY 1.021277 (-625 1800);
PAINT ORANGE (-625 1800);
DISPLAY INVISIBLE (-625 1800);
FORCEADD OFFPAGE..1
(-400 1700);
FORCEPROP 2 LAST $XR0 99 
J 0
(-651 1700);
DISPLAY 0.638298 (-651 1700);
PAINT MONO (-651 1700);
FORCEPROP 2 LAST $XR1 49 
J 0
(-741 1700);
DISPLAY 0.638298 (-741 1700);
PAINT MONO (-741 1700);
FORCEPROP 2 LAST $XR2 51 
J 0
(-831 1700);
DISPLAY 0.638298 (-831 1700);
PAINT MONO (-831 1700);
FORCEPROP 2 LAST $XR3 52 
J 0
(-921 1700);
DISPLAY 0.638298 (-921 1700);
PAINT MONO (-921 1700);
FORCEPROP 2 LAST $XR4 53 
J 0
(-1011 1700);
DISPLAY 0.638298 (-1011 1700);
PAINT MONO (-1011 1700);
FORCEPROP 2 LAST $XR5 54 
J 0
(-1101 1700);
DISPLAY 0.638298 (-1101 1700);
PAINT MONO (-1101 1700);
FORCEPROP 2 LAST CDS_LIB mstr_standard
J 0
(-400 1700);
DISPLAY 0.787234 (-400 1700);
PAINT MONO (-400 1700);
DISPLAY INVISIBLE (-400 1700);
FORCEPROP 1 LAST OFFPAGE TRUE
J 0
(-75 1575);
DISPLAY 0.936170 (-75 1575);
PAINT GREEN (-75 1575);
DISPLAY INVISIBLE (-75 1575);
FORCEPROP 1 LAST COMMENT_BODY TRUE
J 0
(-275 1600);
DISPLAY 0.936170 (-275 1600);
PAINT GREEN (-275 1600);
DISPLAY INVISIBLE (-275 1600);
FORCEPROP 2 LAST PATH I175
J 0
(-650 1750);
DISPLAY 1.021277 (-650 1750);
PAINT ORANGE (-650 1750);
DISPLAY INVISIBLE (-650 1750);
FORCEADD OFFPAGE..1
(-450 1300);
FORCEPROP 2 LAST $XR0 89 
J 0
(-671 1300);
DISPLAY 0.638298 (-671 1300);
PAINT MONO (-671 1300);
FORCEPROP 2 LAST $XR1 49 
J 0
(-761 1300);
DISPLAY 0.638298 (-761 1300);
PAINT MONO (-761 1300);
FORCEPROP 2 LAST $XR2 51 
J 0
(-851 1300);
DISPLAY 0.638298 (-851 1300);
PAINT MONO (-851 1300);
FORCEPROP 2 LAST $XR3 52 
J 0
(-941 1300);
DISPLAY 0.638298 (-941 1300);
PAINT MONO (-941 1300);
FORCEPROP 2 LAST $XR4 53 
J 0
(-1031 1300);
DISPLAY 0.638298 (-1031 1300);
PAINT MONO (-1031 1300);
FORCEPROP 2 LAST $XR5 54 
J 0
(-1121 1300);
DISPLAY 0.638298 (-1121 1300);
PAINT MONO (-1121 1300);
FORCEPROP 2 LAST CDS_LIB mstr_standard
J 0
(-450 1300);
PAINT ORANGE (-450 1300);
DISPLAY INVISIBLE (-450 1300);
FORCEPROP 1 LAST OFFPAGE TRUE
J 0
(-125 1175);
DISPLAY 0.936170 (-125 1175);
PAINT GREEN (-125 1175);
DISPLAY INVISIBLE (-125 1175);
FORCEPROP 1 LAST COMMENT_BODY TRUE
J 0
(-325 1200);
DISPLAY 0.936170 (-325 1200);
PAINT GREEN (-325 1200);
DISPLAY INVISIBLE (-325 1200);
FORCEPROP 2 LAST PATH I176
J 0
(-700 1350);
DISPLAY 1.021277 (-700 1350);
PAINT ORANGE (-700 1350);
DISPLAY INVISIBLE (-700 1350);
FORCEADD CAP_A..1
R 2
(-1200 1400);
FORCEPROP 1 LAST LOCATION C6M1
J 2
(-1250 1500);
DISPLAY 0.617021 (-1250 1500);
PAINT AQUA (-1250 1500);
FORCEPROP 1 LAST PART_NUMBER A36096-045
J 2
(-1250 1250);
DISPLAY 0.617021 (-1250 1250);
PAINT BLUE (-1250 1250);
FORCEPROP 1 LAST VALUE 0.01UF
J 2
(-1250 1450);
DISPLAY 0.617021 (-1250 1450);
PAINT SKYBLUE (-1250 1450);
FORCEPROP 1 LAST TOLERANCE 10%
J 2
(-1250 1350);
DISPLAY 0.617021 (-1250 1350);
PAINT SKYBLUE (-1250 1350);
FORCEPROP 1 LAST PACK_TYPE 0402V
J 2
(-1250 1200);
DISPLAY 0.617021 (-1250 1200);
PAINT SKYBLUE (-1250 1200);
FORCEPROP 1 LAST VOLTAGE 25V
J 2
(-1250 1400);
DISPLAY 0.617021 (-1250 1400);
PAINT SKYBLUE (-1250 1400);
FORCEPROP 1 LAST MATERIAL X7R
J 2
(-1250 1300);
DISPLAY 0.617021 (-1250 1300);
PAINT SKYBLUE (-1250 1300);
FORCEPROP 2 LAST CDS_LOCATION C6M1
J 2
(-1250 1500);
DISPLAY 0.617021 (-1250 1500);
PAINT AQUA (-1250 1500);
DISPLAY INVISIBLE (-1250 1500);
FORCEPROP 2 LAST BOM_COST MEM
J 0
(-1200 1400);
PAINT ORANGE (-1200 1400);
DISPLAY INVISIBLE (-1200 1400);
FORCEPROP 2 LAST CDS_LIB dev_discrete
J 0
(-1200 1400);
PAINT ORANGE (-1200 1400);
DISPLAY INVISIBLE (-1200 1400);
FORCEPROP 2 LAST CDS_SEC 1
J 2
(-1250 1600);
PAINT MONO (-1250 1600);
DISPLAY INVISIBLE (-1250 1600);
FORCEPROP 2 LAST $SEC 1
J 0
(-1250 1600);
PAINT MONO (-1250 1600);
DISPLAY INVISIBLE (-1250 1600);
FORCEPROP 1 LAST PATH I177
J 2
(-1250 1550);
DISPLAY 0.978723 (-1250 1550);
PAINT WHITE (-1250 1550);
DISPLAY INVISIBLE (-1250 1550);
FORCEPROP 2 LAST ROOM DDR4_CH_B
J 0
(-1200 1400);
PAINT ORANGE (-1200 1400);
DISPLAY INVISIBLE (-1200 1400);
FORCEPROP 1 LASTPIN (-1200 1500) $PN 1
J 2
(-1210 1480);
DISPLAY 0.787234 (-1210 1480);
PAINT ORANGE (-1210 1480);
DISPLAY INVISIBLE (-1210 1480);
FORCEPROP 1 LASTPIN (-1200 1300) $PN 2
J 2
(-1210 1280);
DISPLAY 0.787234 (-1210 1280);
PAINT ORANGE (-1210 1280);
DISPLAY INVISIBLE (-1210 1280);
FORCEADD GND..1
(-1200 1150);
FORCEPROP 3 LASTPIN (-1200 1200) SIG_NAME GND\g
J 0
(-1190 1210);
DISPLAY 0.659574 (-1190 1210);
PAINT MONO (-1190 1210);
DISPLAY INVISIBLE (-1190 1210);
FORCEPROP 1 LAST VOLTAGE 0
J 0
(-1200 1150);
PAINT SKYBLUE (-1200 1150);
DISPLAY INVISIBLE (-1200 1150);
FORCEPROP 2 LAST CDS_LIB mstr_symbols
J 0
(-1200 1150);
PAINT ORANGE (-1200 1150);
DISPLAY INVISIBLE (-1200 1150);
FORCEPROP 1 LAST SIZE 1B
J 0
(-1125 1100);
DISPLAY 1.787234 (-1125 1100);
PAINT GREEN (-1125 1100);
DISPLAY INVISIBLE (-1125 1100);
FORCEPROP 2 LAST BOM_COST MEM
J 0
(-1200 1155);
PAINT ORANGE (-1200 1155);
DISPLAY INVISIBLE (-1200 1155);
FORCEPROP 1 LAST BODY_TYPE PLUMBING
J 0
(-1245 1107);
DISPLAY 0.340426 (-1245 1107);
PAINT GREEN (-1245 1107);
DISPLAY INVISIBLE (-1245 1107);
FORCEPROP 1 LAST PATH I178
J 0
(-1125 1150);
DISPLAY 0.872340 (-1125 1150);
PAINT AQUA (-1125 1150);
DISPLAY INVISIBLE (-1125 1150);
FORCEPROP 2 LAST ROOM DDR4_CH_B
J 0
(-1200 1155);
PAINT ORANGE (-1200 1155);
DISPLAY INVISIBLE (-1200 1155);
FORCEPROP 1 LAST HDL_POWER GND
J 0
(-1200 1300);
DISPLAY 1.404255 (-1200 1300);
PAINT GREEN (-1200 1300);
DISPLAY INVISIBLE (-1200 1300);
FORCEADD OFFPAGE..1
(-1350 1600);
FORCEPROP 2 LAST $XR0 98 
J 0
(-1571 1600);
DISPLAY 0.638298 (-1571 1600);
PAINT MONO (-1571 1600);
FORCEPROP 2 LAST $XR1 49 
J 0
(-1661 1600);
DISPLAY 0.638298 (-1661 1600);
PAINT MONO (-1661 1600);
FORCEPROP 2 LAST CDS_LIB mstr_standard
J 0
(-1350 1600);
DISPLAY 0.787234 (-1350 1600);
PAINT MONO (-1350 1600);
DISPLAY INVISIBLE (-1350 1600);
FORCEPROP 1 LAST OFFPAGE TRUE
J 0
(-1025 1475);
DISPLAY 0.936170 (-1025 1475);
PAINT GREEN (-1025 1475);
DISPLAY INVISIBLE (-1025 1475);
FORCEPROP 1 LAST COMMENT_BODY TRUE
J 0
(-1225 1500);
DISPLAY 0.936170 (-1225 1500);
PAINT GREEN (-1225 1500);
DISPLAY INVISIBLE (-1225 1500);
FORCEPROP 2 LAST PATH I179
J 0
(-1550 1650);
DISPLAY 1.021277 (-1550 1650);
PAINT ORANGE (-1550 1650);
DISPLAY INVISIBLE (-1550 1650);
FORCEADD TAP..6
R 2
(4100 4100);
FORCEPROP 3 LASTPIN (4050 4100) SIG_NAME M_D_DQS_DP<10>
J 0
(4060 4110);
DISPLAY 0.659574 (4060 4110);
PAINT MONO (4060 4110);
DISPLAY INVISIBLE (4060 4110);
FORCEPROP 1 LASTPIN (4050 4100) BN 10
J 2
(4100 4110);
DISPLAY 0.617021 (4100 4110);
PAINT PINK (4100 4110);
FORCEPROP 2 LAST CDS_LIB mstr_standard
J 0
(4100 4100);
DISPLAY 0.787234 (4100 4100);
PAINT MONO (4100 4100);
DISPLAY INVISIBLE (4100 4100);
FORCEPROP 1 LAST BODY_TYPE PLUMBING
J 2
(4100 4050);
DISPLAY 1.234043 (4100 4050);
PAINT GREEN (4100 4050);
DISPLAY INVISIBLE (4100 4050);
FORCEPROP 1 LAST HDL_TAP TRUE
J 2
(3775 3975);
DISPLAY 1.234043 (3775 3975);
PAINT GREEN (3775 3975);
DISPLAY INVISIBLE (3775 3975);
FORCEPROP 1 LAST PATH I18
J 2
(4102 4100);
DISPLAY 0.872340 (4102 4100);
PAINT GREEN (4102 4100);
DISPLAY INVISIBLE (4102 4100);
FORCEADD GND..1
(-1350 1775);
FORCEPROP 3 LASTPIN (-1350 1825) SIG_NAME GND\g
J 0
(-1340 1835);
DISPLAY 0.659574 (-1340 1835);
PAINT MONO (-1340 1835);
DISPLAY INVISIBLE (-1340 1835);
FORCEPROP 1 LAST VOLTAGE 0
J 0
(-1350 1775);
PAINT SKYBLUE (-1350 1775);
DISPLAY INVISIBLE (-1350 1775);
FORCEPROP 2 LAST BOM_COST MEM
J 0
(-1350 1780);
PAINT ORANGE (-1350 1780);
DISPLAY INVISIBLE (-1350 1780);
FORCEPROP 1 LAST SIZE 1B
J 0
(-1275 1725);
DISPLAY 1.787234 (-1275 1725);
PAINT GREEN (-1275 1725);
DISPLAY INVISIBLE (-1275 1725);
FORCEPROP 2 LAST CDS_LIB mstr_symbols
J 0
(-1350 1775);
PAINT ORANGE (-1350 1775);
DISPLAY INVISIBLE (-1350 1775);
FORCEPROP 1 LAST BODY_TYPE PLUMBING
J 0
(-1395 1732);
DISPLAY 0.340426 (-1395 1732);
PAINT GREEN (-1395 1732);
DISPLAY INVISIBLE (-1395 1732);
FORCEPROP 1 LAST PATH I180
J 0
(-1275 1775);
DISPLAY 0.872340 (-1275 1775);
PAINT AQUA (-1275 1775);
DISPLAY INVISIBLE (-1275 1775);
FORCEPROP 2 LAST ROOM DDR4_CH_B
J 0
(-1350 1780);
PAINT ORANGE (-1350 1780);
DISPLAY INVISIBLE (-1350 1780);
FORCEPROP 1 LAST HDL_POWER GND
J 0
(-1350 1925);
DISPLAY 1.404255 (-1350 1925);
PAINT GREEN (-1350 1925);
DISPLAY INVISIBLE (-1350 1925);
FORCEADD P12V_NVDIMM_DEF..1
(4100 2625);
FORCEPROP 3 LASTPIN (4100 2575) SIG_NAME P12V_NVDIMM_DEF\g
J 0
(4110 2585);
DISPLAY 0.659574 (4110 2585);
PAINT MONO (4110 2585);
DISPLAY INVISIBLE (4110 2585);
FORCEPROP 1 LAST VOLTAGE 12.0
J 0
(4055 2582);
DISPLAY 0.340426 (4055 2582);
PAINT SKYBLUE (4055 2582);
DISPLAY INVISIBLE (4055 2582);
FORCEPROP 2 LAST CDS_LIB mstr_symbols
J 0
(4100 2625);
PAINT ORANGE (4100 2625);
DISPLAY INVISIBLE (4100 2625);
FORCEPROP 1 LAST BODY_TYPE PLUMBING
J 0
(4055 2582);
DISPLAY 0.340426 (4055 2582);
PAINT GREEN (4055 2582);
DISPLAY INVISIBLE (4055 2582);
FORCEPROP 1 LAST PATH I181
J 0
(4150 2650);
DISPLAY 0.872340 (4150 2650);
PAINT AQUA (4150 2650);
DISPLAY INVISIBLE (4150 2650);
FORCEPROP 1 LAST HDL_POWER P12V_NVDIMM_DEF
J 1
(4100 2675);
DISPLAY 0.872340 (4100 2675);
PAINT GREEN (4100 2675);
DISPLAY INVISIBLE (4100 2675);
FORCEADD OFFPAGE..3
(2250 4800);
FORCEPROP 2 LAST $XR0 26 
J 0
(2464 4800);
DISPLAY 0.638298 (2464 4800);
PAINT MONO (2464 4800);
FORCEPROP 2 LAST $XR1 49 
J 0
(2554 4800);
DISPLAY 0.638298 (2554 4800);
PAINT MONO (2554 4800);
FORCEPROP 2 LAST CDS_LIB mstr_standard
J 0
(2250 4800);
DISPLAY 0.787234 (2250 4800);
PAINT MONO (2250 4800);
DISPLAY INVISIBLE (2250 4800);
FORCEPROP 1 LAST OFFPAGE TRUE
J 0
(2575 4675);
DISPLAY 0.936170 (2575 4675);
PAINT GREEN (2575 4675);
DISPLAY INVISIBLE (2575 4675);
FORCEPROP 1 LAST COMMENT_BODY TRUE
J 0
(2200 4700);
DISPLAY 0.936170 (2200 4700);
PAINT GREEN (2200 4700);
DISPLAY INVISIBLE (2200 4700);
FORCEPROP 2 LAST PATH I19
J 0
(2575 4850);
DISPLAY 1.021277 (2575 4850);
PAINT ORANGE (2575 4850);
DISPLAY INVISIBLE (2575 4850);
FORCEADD OFFPAGE..3
(5100 4850);
FORCEPROP 2 LAST $XR0 26 
J 0
(5314 4850);
DISPLAY 0.638298 (5314 4850);
PAINT MONO (5314 4850);
FORCEPROP 2 LAST $XR1 49 
J 0
(5404 4850);
DISPLAY 0.638298 (5404 4850);
PAINT MONO (5404 4850);
FORCEPROP 2 LAST CDS_LIB mstr_standard
J 0
(5100 4850);
DISPLAY 0.787234 (5100 4850);
PAINT MONO (5100 4850);
DISPLAY INVISIBLE (5100 4850);
FORCEPROP 1 LAST OFFPAGE TRUE
J 0
(5425 4725);
DISPLAY 0.936170 (5425 4725);
PAINT GREEN (5425 4725);
DISPLAY INVISIBLE (5425 4725);
FORCEPROP 1 LAST COMMENT_BODY TRUE
J 0
(5050 4750);
DISPLAY 0.936170 (5050 4750);
PAINT GREEN (5050 4750);
DISPLAY INVISIBLE (5050 4750);
FORCEPROP 2 LAST PATH I2
J 0
(5425 4900);
DISPLAY 1.021277 (5425 4900);
PAINT ORANGE (5425 4900);
DISPLAY INVISIBLE (5425 4900);
FORCEADD TAP..6
R 2
(4350 3950);
FORCEPROP 3 LASTPIN (4300 3950) SIG_NAME M_D_DQS_DN<9>
J 0
(4310 3960);
DISPLAY 0.659574 (4310 3960);
PAINT MONO (4310 3960);
DISPLAY INVISIBLE (4310 3960);
FORCEPROP 1 LASTPIN (4300 3950) BN 9
J 2
(4350 3960);
DISPLAY 0.617021 (4350 3960);
PAINT PINK (4350 3960);
FORCEPROP 2 LAST CDS_LIB mstr_standard
J 0
(4350 3950);
DISPLAY 0.787234 (4350 3950);
PAINT MONO (4350 3950);
DISPLAY INVISIBLE (4350 3950);
FORCEPROP 1 LAST BODY_TYPE PLUMBING
J 2
(4350 3900);
DISPLAY 1.234043 (4350 3900);
PAINT GREEN (4350 3900);
DISPLAY INVISIBLE (4350 3900);
FORCEPROP 1 LAST HDL_TAP TRUE
J 2
(4025 3825);
DISPLAY 1.234043 (4025 3825);
PAINT GREEN (4025 3825);
DISPLAY INVISIBLE (4025 3825);
FORCEPROP 1 LAST PATH I20
J 2
(4352 3950);
DISPLAY 0.872340 (4352 3950);
PAINT GREEN (4352 3950);
DISPLAY INVISIBLE (4352 3950);
FORCEADD TAP..6
R 2
(4350 4050);
FORCEPROP 3 LASTPIN (4300 4050) SIG_NAME M_D_DQS_DN<10>
J 0
(4310 4060);
DISPLAY 0.659574 (4310 4060);
PAINT MONO (4310 4060);
DISPLAY INVISIBLE (4310 4060);
FORCEPROP 1 LASTPIN (4300 4050) BN 10
J 2
(4350 4060);
DISPLAY 0.617021 (4350 4060);
PAINT PINK (4350 4060);
FORCEPROP 2 LAST CDS_LIB mstr_standard
J 0
(4350 4050);
DISPLAY 0.787234 (4350 4050);
PAINT MONO (4350 4050);
DISPLAY INVISIBLE (4350 4050);
FORCEPROP 1 LAST BODY_TYPE PLUMBING
J 2
(4350 4000);
DISPLAY 1.234043 (4350 4000);
PAINT GREEN (4350 4000);
DISPLAY INVISIBLE (4350 4000);
FORCEPROP 1 LAST HDL_TAP TRUE
J 2
(4025 3925);
DISPLAY 1.234043 (4025 3925);
PAINT GREEN (4025 3925);
DISPLAY INVISIBLE (4025 3925);
FORCEPROP 1 LAST PATH I21
J 2
(4352 4050);
DISPLAY 0.872340 (4352 4050);
PAINT GREEN (4352 4050);
DISPLAY INVISIBLE (4352 4050);
FORCEADD TAP..6
R 2
(4350 3850);
FORCEPROP 3 LASTPIN (4300 3850) SIG_NAME M_D_DQS_DN<8>
J 0
(4310 3860);
DISPLAY 0.659574 (4310 3860);
PAINT MONO (4310 3860);
DISPLAY INVISIBLE (4310 3860);
FORCEPROP 1 LASTPIN (4300 3850) BN 8
J 2
(4350 3860);
DISPLAY 0.617021 (4350 3860);
PAINT PINK (4350 3860);
FORCEPROP 2 LAST CDS_LIB mstr_standard
J 0
(4350 3850);
DISPLAY 0.787234 (4350 3850);
PAINT MONO (4350 3850);
DISPLAY INVISIBLE (4350 3850);
FORCEPROP 1 LAST BODY_TYPE PLUMBING
J 2
(4350 3800);
DISPLAY 1.234043 (4350 3800);
PAINT GREEN (4350 3800);
DISPLAY INVISIBLE (4350 3800);
FORCEPROP 1 LAST HDL_TAP TRUE
J 2
(4025 3725);
DISPLAY 1.234043 (4025 3725);
PAINT GREEN (4025 3725);
DISPLAY INVISIBLE (4025 3725);
FORCEPROP 1 LAST PATH I22
J 2
(4352 3850);
DISPLAY 0.872340 (4352 3850);
PAINT GREEN (4352 3850);
DISPLAY INVISIBLE (4352 3850);
FORCEADD TAP..6
R 2
(4350 3750);
FORCEPROP 3 LASTPIN (4300 3750) SIG_NAME M_D_DQS_DN<7>
J 0
(4310 3760);
DISPLAY 0.659574 (4310 3760);
PAINT MONO (4310 3760);
DISPLAY INVISIBLE (4310 3760);
FORCEPROP 1 LASTPIN (4300 3750) BN 7
J 2
(4350 3760);
DISPLAY 0.617021 (4350 3760);
PAINT PINK (4350 3760);
FORCEPROP 2 LAST CDS_LIB mstr_standard
J 0
(4350 3750);
DISPLAY 0.787234 (4350 3750);
PAINT MONO (4350 3750);
DISPLAY INVISIBLE (4350 3750);
FORCEPROP 1 LAST BODY_TYPE PLUMBING
J 2
(4350 3700);
DISPLAY 1.234043 (4350 3700);
PAINT GREEN (4350 3700);
DISPLAY INVISIBLE (4350 3700);
FORCEPROP 1 LAST HDL_TAP TRUE
J 2
(4025 3625);
DISPLAY 1.234043 (4025 3625);
PAINT GREEN (4025 3625);
DISPLAY INVISIBLE (4025 3625);
FORCEPROP 1 LAST PATH I23
J 2
(4352 3750);
DISPLAY 0.872340 (4352 3750);
PAINT GREEN (4352 3750);
DISPLAY INVISIBLE (4352 3750);
FORCEADD TAP..6
R 2
(4350 3650);
FORCEPROP 3 LASTPIN (4300 3650) SIG_NAME M_D_DQS_DN<6>
J 0
(4310 3660);
DISPLAY 0.659574 (4310 3660);
PAINT MONO (4310 3660);
DISPLAY INVISIBLE (4310 3660);
FORCEPROP 1 LASTPIN (4300 3650) BN 6
J 2
(4350 3660);
DISPLAY 0.617021 (4350 3660);
PAINT PINK (4350 3660);
FORCEPROP 2 LAST CDS_LIB mstr_standard
J 0
(4350 3650);
DISPLAY 0.787234 (4350 3650);
PAINT MONO (4350 3650);
DISPLAY INVISIBLE (4350 3650);
FORCEPROP 1 LAST BODY_TYPE PLUMBING
J 2
(4350 3600);
DISPLAY 1.234043 (4350 3600);
PAINT GREEN (4350 3600);
DISPLAY INVISIBLE (4350 3600);
FORCEPROP 1 LAST HDL_TAP TRUE
J 2
(4025 3525);
DISPLAY 1.234043 (4025 3525);
PAINT GREEN (4025 3525);
DISPLAY INVISIBLE (4025 3525);
FORCEPROP 1 LAST PATH I24
J 2
(4352 3650);
DISPLAY 0.872340 (4352 3650);
PAINT GREEN (4352 3650);
DISPLAY INVISIBLE (4352 3650);
FORCEADD TAP..6
R 2
(4100 4000);
FORCEPROP 3 LASTPIN (4050 4000) SIG_NAME M_D_DQS_DP<9>
J 0
(4060 4010);
DISPLAY 0.659574 (4060 4010);
PAINT MONO (4060 4010);
DISPLAY INVISIBLE (4060 4010);
FORCEPROP 1 LASTPIN (4050 4000) BN 9
J 2
(4100 4010);
DISPLAY 0.617021 (4100 4010);
PAINT PINK (4100 4010);
FORCEPROP 2 LAST CDS_LIB mstr_standard
J 0
(4100 4000);
DISPLAY 0.787234 (4100 4000);
PAINT MONO (4100 4000);
DISPLAY INVISIBLE (4100 4000);
FORCEPROP 1 LAST BODY_TYPE PLUMBING
J 2
(4100 3950);
DISPLAY 1.234043 (4100 3950);
PAINT GREEN (4100 3950);
DISPLAY INVISIBLE (4100 3950);
FORCEPROP 1 LAST HDL_TAP TRUE
J 2
(3775 3875);
DISPLAY 1.234043 (3775 3875);
PAINT GREEN (3775 3875);
DISPLAY INVISIBLE (3775 3875);
FORCEPROP 1 LAST PATH I25
J 2
(4102 4000);
DISPLAY 0.872340 (4102 4000);
PAINT GREEN (4102 4000);
DISPLAY INVISIBLE (4102 4000);
FORCEADD TAP..6
R 2
(4100 3900);
FORCEPROP 3 LASTPIN (4050 3900) SIG_NAME M_D_DQS_DP<8>
J 0
(4060 3910);
DISPLAY 0.659574 (4060 3910);
PAINT MONO (4060 3910);
DISPLAY INVISIBLE (4060 3910);
FORCEPROP 1 LASTPIN (4050 3900) BN 8
J 2
(4100 3910);
DISPLAY 0.617021 (4100 3910);
PAINT PINK (4100 3910);
FORCEPROP 2 LAST CDS_LIB mstr_standard
J 0
(4100 3900);
DISPLAY 0.787234 (4100 3900);
PAINT MONO (4100 3900);
DISPLAY INVISIBLE (4100 3900);
FORCEPROP 1 LAST BODY_TYPE PLUMBING
J 2
(4100 3850);
DISPLAY 1.234043 (4100 3850);
PAINT GREEN (4100 3850);
DISPLAY INVISIBLE (4100 3850);
FORCEPROP 1 LAST HDL_TAP TRUE
J 2
(3775 3775);
DISPLAY 1.234043 (3775 3775);
PAINT GREEN (3775 3775);
DISPLAY INVISIBLE (3775 3775);
FORCEPROP 1 LAST PATH I26
J 2
(4102 3900);
DISPLAY 0.872340 (4102 3900);
PAINT GREEN (4102 3900);
DISPLAY INVISIBLE (4102 3900);
FORCEADD TAP..6
R 2
(4100 3700);
FORCEPROP 3 LASTPIN (4050 3700) SIG_NAME M_D_DQS_DP<6>
J 0
(4060 3710);
DISPLAY 0.659574 (4060 3710);
PAINT MONO (4060 3710);
DISPLAY INVISIBLE (4060 3710);
FORCEPROP 1 LASTPIN (4050 3700) BN 6
J 2
(4100 3710);
DISPLAY 0.617021 (4100 3710);
PAINT PINK (4100 3710);
FORCEPROP 2 LAST CDS_LIB mstr_standard
J 0
(4100 3700);
DISPLAY 0.787234 (4100 3700);
PAINT MONO (4100 3700);
DISPLAY INVISIBLE (4100 3700);
FORCEPROP 1 LAST BODY_TYPE PLUMBING
J 2
(4100 3650);
DISPLAY 1.234043 (4100 3650);
PAINT GREEN (4100 3650);
DISPLAY INVISIBLE (4100 3650);
FORCEPROP 1 LAST HDL_TAP TRUE
J 2
(3775 3575);
DISPLAY 1.234043 (3775 3575);
PAINT GREEN (3775 3575);
DISPLAY INVISIBLE (3775 3575);
FORCEPROP 1 LAST PATH I27
J 2
(4102 3700);
DISPLAY 0.872340 (4102 3700);
PAINT GREEN (4102 3700);
DISPLAY INVISIBLE (4102 3700);
FORCEADD TAP..6
R 2
(4100 3800);
FORCEPROP 3 LASTPIN (4050 3800) SIG_NAME M_D_DQS_DP<7>
J 0
(4060 3810);
DISPLAY 0.659574 (4060 3810);
PAINT MONO (4060 3810);
DISPLAY INVISIBLE (4060 3810);
FORCEPROP 1 LASTPIN (4050 3800) BN 7
J 2
(4100 3810);
DISPLAY 0.617021 (4100 3810);
PAINT PINK (4100 3810);
FORCEPROP 2 LAST CDS_LIB mstr_standard
J 0
(4100 3800);
DISPLAY 0.787234 (4100 3800);
PAINT MONO (4100 3800);
DISPLAY INVISIBLE (4100 3800);
FORCEPROP 1 LAST BODY_TYPE PLUMBING
J 2
(4100 3750);
DISPLAY 1.234043 (4100 3750);
PAINT GREEN (4100 3750);
DISPLAY INVISIBLE (4100 3750);
FORCEPROP 1 LAST HDL_TAP TRUE
J 2
(3775 3675);
DISPLAY 1.234043 (3775 3675);
PAINT GREEN (3775 3675);
DISPLAY INVISIBLE (3775 3675);
FORCEPROP 1 LAST PATH I28
J 2
(4102 3800);
DISPLAY 0.872340 (4102 3800);
PAINT GREEN (4102 3800);
DISPLAY INVISIBLE (4102 3800);
FORCEADD TAP..6
R 2
(4100 3600);
FORCEPROP 3 LASTPIN (4050 3600) SIG_NAME M_D_DQS_DP<5>
J 0
(4060 3610);
DISPLAY 0.659574 (4060 3610);
PAINT MONO (4060 3610);
DISPLAY INVISIBLE (4060 3610);
FORCEPROP 1 LASTPIN (4050 3600) BN 5
J 2
(4100 3610);
DISPLAY 0.617021 (4100 3610);
PAINT PINK (4100 3610);
FORCEPROP 2 LAST CDS_LIB mstr_standard
J 0
(4100 3600);
DISPLAY 0.787234 (4100 3600);
PAINT MONO (4100 3600);
DISPLAY INVISIBLE (4100 3600);
FORCEPROP 1 LAST BODY_TYPE PLUMBING
J 2
(4100 3550);
DISPLAY 1.234043 (4100 3550);
PAINT GREEN (4100 3550);
DISPLAY INVISIBLE (4100 3550);
FORCEPROP 1 LAST HDL_TAP TRUE
J 2
(3775 3475);
DISPLAY 1.234043 (3775 3475);
PAINT GREEN (3775 3475);
DISPLAY INVISIBLE (3775 3475);
FORCEPROP 1 LAST PATH I29
J 2
(4102 3600);
DISPLAY 0.872340 (4102 3600);
PAINT GREEN (4102 3600);
DISPLAY INVISIBLE (4102 3600);
FORCEADD OFFPAGE..3
(5100 4800);
FORCEPROP 2 LAST $XR0 26 
J 0
(5314 4800);
DISPLAY 0.638298 (5314 4800);
PAINT MONO (5314 4800);
FORCEPROP 2 LAST $XR1 49 
J 0
(5404 4800);
DISPLAY 0.638298 (5404 4800);
PAINT MONO (5404 4800);
FORCEPROP 2 LAST CDS_LIB mstr_standard
J 0
(5100 4800);
DISPLAY 0.787234 (5100 4800);
PAINT MONO (5100 4800);
DISPLAY INVISIBLE (5100 4800);
FORCEPROP 1 LAST OFFPAGE TRUE
J 0
(5425 4675);
DISPLAY 0.936170 (5425 4675);
PAINT GREEN (5425 4675);
DISPLAY INVISIBLE (5425 4675);
FORCEPROP 1 LAST COMMENT_BODY TRUE
J 0
(5050 4700);
DISPLAY 0.936170 (5050 4700);
PAINT GREEN (5050 4700);
DISPLAY INVISIBLE (5050 4700);
FORCEPROP 2 LAST PATH I3
J 0
(5425 4850);
DISPLAY 1.021277 (5425 4850);
PAINT ORANGE (5425 4850);
DISPLAY INVISIBLE (5425 4850);
FORCEADD TAP..6
R 2
(4350 3550);
FORCEPROP 3 LASTPIN (4300 3550) SIG_NAME M_D_DQS_DN<5>
J 0
(4310 3560);
DISPLAY 0.659574 (4310 3560);
PAINT MONO (4310 3560);
DISPLAY INVISIBLE (4310 3560);
FORCEPROP 1 LASTPIN (4300 3550) BN 5
J 2
(4350 3560);
DISPLAY 0.617021 (4350 3560);
PAINT PINK (4350 3560);
FORCEPROP 2 LAST CDS_LIB mstr_standard
J 0
(4350 3550);
DISPLAY 0.787234 (4350 3550);
PAINT MONO (4350 3550);
DISPLAY INVISIBLE (4350 3550);
FORCEPROP 1 LAST BODY_TYPE PLUMBING
J 2
(4350 3500);
DISPLAY 1.234043 (4350 3500);
PAINT GREEN (4350 3500);
DISPLAY INVISIBLE (4350 3500);
FORCEPROP 1 LAST HDL_TAP TRUE
J 2
(4025 3425);
DISPLAY 1.234043 (4025 3425);
PAINT GREEN (4025 3425);
DISPLAY INVISIBLE (4025 3425);
FORCEPROP 1 LAST PATH I30
J 2
(4352 3550);
DISPLAY 0.872340 (4352 3550);
PAINT GREEN (4352 3550);
DISPLAY INVISIBLE (4352 3550);
FORCEADD TAP..6
R 2
(4350 3450);
FORCEPROP 3 LASTPIN (4300 3450) SIG_NAME M_D_DQS_DN<4>
J 0
(4310 3460);
DISPLAY 0.659574 (4310 3460);
PAINT MONO (4310 3460);
DISPLAY INVISIBLE (4310 3460);
FORCEPROP 1 LASTPIN (4300 3450) BN 4
J 2
(4350 3460);
DISPLAY 0.617021 (4350 3460);
PAINT PINK (4350 3460);
FORCEPROP 2 LAST CDS_LIB mstr_standard
J 0
(4350 3450);
DISPLAY 0.787234 (4350 3450);
PAINT MONO (4350 3450);
DISPLAY INVISIBLE (4350 3450);
FORCEPROP 1 LAST BODY_TYPE PLUMBING
J 2
(4350 3400);
DISPLAY 1.234043 (4350 3400);
PAINT GREEN (4350 3400);
DISPLAY INVISIBLE (4350 3400);
FORCEPROP 1 LAST HDL_TAP TRUE
J 2
(4025 3325);
DISPLAY 1.234043 (4025 3325);
PAINT GREEN (4025 3325);
DISPLAY INVISIBLE (4025 3325);
FORCEPROP 1 LAST PATH I31
J 2
(4352 3450);
DISPLAY 0.872340 (4352 3450);
PAINT GREEN (4352 3450);
DISPLAY INVISIBLE (4352 3450);
FORCEADD TAP..6
R 2
(4350 3350);
FORCEPROP 3 LASTPIN (4300 3350) SIG_NAME M_D_DQS_DN<3>
J 0
(4310 3360);
DISPLAY 0.659574 (4310 3360);
PAINT MONO (4310 3360);
DISPLAY INVISIBLE (4310 3360);
FORCEPROP 1 LASTPIN (4300 3350) BN 3
J 2
(4350 3360);
DISPLAY 0.617021 (4350 3360);
PAINT PINK (4350 3360);
FORCEPROP 2 LAST CDS_LIB mstr_standard
J 0
(4350 3350);
DISPLAY 0.787234 (4350 3350);
PAINT MONO (4350 3350);
DISPLAY INVISIBLE (4350 3350);
FORCEPROP 1 LAST BODY_TYPE PLUMBING
J 2
(4350 3300);
DISPLAY 1.234043 (4350 3300);
PAINT GREEN (4350 3300);
DISPLAY INVISIBLE (4350 3300);
FORCEPROP 1 LAST HDL_TAP TRUE
J 2
(4025 3225);
DISPLAY 1.234043 (4025 3225);
PAINT GREEN (4025 3225);
DISPLAY INVISIBLE (4025 3225);
FORCEPROP 1 LAST PATH I32
J 2
(4352 3350);
DISPLAY 0.872340 (4352 3350);
PAINT GREEN (4352 3350);
DISPLAY INVISIBLE (4352 3350);
FORCEADD TAP..6
R 2
(4350 3250);
FORCEPROP 3 LASTPIN (4300 3250) SIG_NAME M_D_DQS_DN<2>
J 0
(4310 3260);
DISPLAY 0.659574 (4310 3260);
PAINT MONO (4310 3260);
DISPLAY INVISIBLE (4310 3260);
FORCEPROP 1 LASTPIN (4300 3250) BN 2
J 2
(4350 3260);
DISPLAY 0.617021 (4350 3260);
PAINT PINK (4350 3260);
FORCEPROP 2 LAST CDS_LIB mstr_standard
J 0
(4350 3250);
DISPLAY 0.787234 (4350 3250);
PAINT MONO (4350 3250);
DISPLAY INVISIBLE (4350 3250);
FORCEPROP 1 LAST BODY_TYPE PLUMBING
J 2
(4350 3200);
DISPLAY 1.234043 (4350 3200);
PAINT GREEN (4350 3200);
DISPLAY INVISIBLE (4350 3200);
FORCEPROP 1 LAST HDL_TAP TRUE
J 2
(4025 3125);
DISPLAY 1.234043 (4025 3125);
PAINT GREEN (4025 3125);
DISPLAY INVISIBLE (4025 3125);
FORCEPROP 1 LAST PATH I33
J 2
(4352 3250);
DISPLAY 0.872340 (4352 3250);
PAINT GREEN (4352 3250);
DISPLAY INVISIBLE (4352 3250);
FORCEADD TAP..6
R 2
(4350 3050);
FORCEPROP 3 LASTPIN (4300 3050) SIG_NAME M_D_DQS_DN<0>
J 0
(4310 3060);
DISPLAY 0.659574 (4310 3060);
PAINT MONO (4310 3060);
DISPLAY INVISIBLE (4310 3060);
FORCEPROP 1 LASTPIN (4300 3050) BN 0
J 2
(4350 3060);
DISPLAY 0.617021 (4350 3060);
PAINT PINK (4350 3060);
FORCEPROP 2 LAST CDS_LIB mstr_standard
J 0
(4350 3050);
DISPLAY 0.787234 (4350 3050);
PAINT MONO (4350 3050);
DISPLAY INVISIBLE (4350 3050);
FORCEPROP 1 LAST BODY_TYPE PLUMBING
J 2
(4350 3000);
DISPLAY 1.234043 (4350 3000);
PAINT GREEN (4350 3000);
DISPLAY INVISIBLE (4350 3000);
FORCEPROP 1 LAST HDL_TAP TRUE
J 2
(4025 2925);
DISPLAY 1.234043 (4025 2925);
PAINT GREEN (4025 2925);
DISPLAY INVISIBLE (4025 2925);
FORCEPROP 1 LAST PATH I34
J 2
(4352 3050);
DISPLAY 0.872340 (4352 3050);
PAINT GREEN (4352 3050);
DISPLAY INVISIBLE (4352 3050);
FORCEADD TAP..6
R 2
(4350 3150);
FORCEPROP 3 LASTPIN (4300 3150) SIG_NAME M_D_DQS_DN<1>
J 0
(4310 3160);
DISPLAY 0.659574 (4310 3160);
PAINT MONO (4310 3160);
DISPLAY INVISIBLE (4310 3160);
FORCEPROP 1 LASTPIN (4300 3150) BN 1
J 2
(4350 3160);
DISPLAY 0.617021 (4350 3160);
PAINT PINK (4350 3160);
FORCEPROP 2 LAST CDS_LIB mstr_standard
J 0
(4350 3150);
DISPLAY 0.787234 (4350 3150);
PAINT MONO (4350 3150);
DISPLAY INVISIBLE (4350 3150);
FORCEPROP 1 LAST BODY_TYPE PLUMBING
J 2
(4350 3100);
DISPLAY 1.234043 (4350 3100);
PAINT GREEN (4350 3100);
DISPLAY INVISIBLE (4350 3100);
FORCEPROP 1 LAST HDL_TAP TRUE
J 2
(4025 3025);
DISPLAY 1.234043 (4025 3025);
PAINT GREEN (4025 3025);
DISPLAY INVISIBLE (4025 3025);
FORCEPROP 1 LAST PATH I35
J 2
(4352 3150);
DISPLAY 0.872340 (4352 3150);
PAINT GREEN (4352 3150);
DISPLAY INVISIBLE (4352 3150);
FORCEADD TAP..6
R 2
(4100 3500);
FORCEPROP 3 LASTPIN (4050 3500) SIG_NAME M_D_DQS_DP<4>
J 0
(4060 3510);
DISPLAY 0.659574 (4060 3510);
PAINT MONO (4060 3510);
DISPLAY INVISIBLE (4060 3510);
FORCEPROP 1 LASTPIN (4050 3500) BN 4
J 2
(4100 3510);
DISPLAY 0.617021 (4100 3510);
PAINT PINK (4100 3510);
FORCEPROP 2 LAST CDS_LIB mstr_standard
J 0
(4100 3500);
DISPLAY 0.787234 (4100 3500);
PAINT MONO (4100 3500);
DISPLAY INVISIBLE (4100 3500);
FORCEPROP 1 LAST BODY_TYPE PLUMBING
J 2
(4100 3450);
DISPLAY 1.234043 (4100 3450);
PAINT GREEN (4100 3450);
DISPLAY INVISIBLE (4100 3450);
FORCEPROP 1 LAST HDL_TAP TRUE
J 2
(3775 3375);
DISPLAY 1.234043 (3775 3375);
PAINT GREEN (3775 3375);
DISPLAY INVISIBLE (3775 3375);
FORCEPROP 1 LAST PATH I36
J 2
(4102 3500);
DISPLAY 0.872340 (4102 3500);
PAINT GREEN (4102 3500);
DISPLAY INVISIBLE (4102 3500);
FORCEADD TAP..6
R 2
(4100 3400);
FORCEPROP 3 LASTPIN (4050 3400) SIG_NAME M_D_DQS_DP<3>
J 0
(4060 3410);
DISPLAY 0.659574 (4060 3410);
PAINT MONO (4060 3410);
DISPLAY INVISIBLE (4060 3410);
FORCEPROP 1 LASTPIN (4050 3400) BN 3
J 2
(4100 3410);
DISPLAY 0.617021 (4100 3410);
PAINT PINK (4100 3410);
FORCEPROP 2 LAST CDS_LIB mstr_standard
J 0
(4100 3400);
DISPLAY 0.787234 (4100 3400);
PAINT MONO (4100 3400);
DISPLAY INVISIBLE (4100 3400);
FORCEPROP 1 LAST BODY_TYPE PLUMBING
J 2
(4100 3350);
DISPLAY 1.234043 (4100 3350);
PAINT GREEN (4100 3350);
DISPLAY INVISIBLE (4100 3350);
FORCEPROP 1 LAST HDL_TAP TRUE
J 2
(3775 3275);
DISPLAY 1.234043 (3775 3275);
PAINT GREEN (3775 3275);
DISPLAY INVISIBLE (3775 3275);
FORCEPROP 1 LAST PATH I37
J 2
(4102 3400);
DISPLAY 0.872340 (4102 3400);
PAINT GREEN (4102 3400);
DISPLAY INVISIBLE (4102 3400);
FORCEADD TAP..6
R 2
(4100 3300);
FORCEPROP 3 LASTPIN (4050 3300) SIG_NAME M_D_DQS_DP<2>
J 0
(4060 3310);
DISPLAY 0.659574 (4060 3310);
PAINT MONO (4060 3310);
DISPLAY INVISIBLE (4060 3310);
FORCEPROP 1 LASTPIN (4050 3300) BN 2
J 2
(4100 3310);
DISPLAY 0.617021 (4100 3310);
PAINT PINK (4100 3310);
FORCEPROP 2 LAST CDS_LIB mstr_standard
J 0
(4100 3300);
DISPLAY 0.787234 (4100 3300);
PAINT MONO (4100 3300);
DISPLAY INVISIBLE (4100 3300);
FORCEPROP 1 LAST BODY_TYPE PLUMBING
J 2
(4100 3250);
DISPLAY 1.234043 (4100 3250);
PAINT GREEN (4100 3250);
DISPLAY INVISIBLE (4100 3250);
FORCEPROP 1 LAST HDL_TAP TRUE
J 2
(3775 3175);
DISPLAY 1.234043 (3775 3175);
PAINT GREEN (3775 3175);
DISPLAY INVISIBLE (3775 3175);
FORCEPROP 1 LAST PATH I38
J 2
(4102 3300);
DISPLAY 0.872340 (4102 3300);
PAINT GREEN (4102 3300);
DISPLAY INVISIBLE (4102 3300);
FORCEADD TAP..6
R 2
(4100 3200);
FORCEPROP 3 LASTPIN (4050 3200) SIG_NAME M_D_DQS_DP<1>
J 0
(4060 3210);
DISPLAY 0.659574 (4060 3210);
PAINT MONO (4060 3210);
DISPLAY INVISIBLE (4060 3210);
FORCEPROP 1 LASTPIN (4050 3200) BN 1
J 2
(4100 3210);
DISPLAY 0.617021 (4100 3210);
PAINT PINK (4100 3210);
FORCEPROP 2 LAST CDS_LIB mstr_standard
J 0
(4100 3200);
DISPLAY 0.787234 (4100 3200);
PAINT MONO (4100 3200);
DISPLAY INVISIBLE (4100 3200);
FORCEPROP 1 LAST BODY_TYPE PLUMBING
J 2
(4100 3150);
DISPLAY 1.234043 (4100 3150);
PAINT GREEN (4100 3150);
DISPLAY INVISIBLE (4100 3150);
FORCEPROP 1 LAST HDL_TAP TRUE
J 2
(3775 3075);
DISPLAY 1.234043 (3775 3075);
PAINT GREEN (3775 3075);
DISPLAY INVISIBLE (3775 3075);
FORCEPROP 1 LAST PATH I39
J 2
(4102 3200);
DISPLAY 0.872340 (4102 3200);
PAINT GREEN (4102 3200);
DISPLAY INVISIBLE (4102 3200);
FORCEADD TAP..6
R 2
(4350 4750);
FORCEPROP 3 LASTPIN (4300 4750) SIG_NAME M_D_DQS_DN<17>
J 0
(4310 4760);
DISPLAY 0.659574 (4310 4760);
PAINT MONO (4310 4760);
DISPLAY INVISIBLE (4310 4760);
FORCEPROP 1 LASTPIN (4300 4750) BN 17
J 2
(4350 4760);
DISPLAY 0.617021 (4350 4760);
PAINT PINK (4350 4760);
FORCEPROP 2 LAST CDS_LIB mstr_standard
J 2
(4350 4750);
DISPLAY 0.787234 (4350 4750);
PAINT MONO (4350 4750);
DISPLAY INVISIBLE (4350 4750);
FORCEPROP 1 LAST BODY_TYPE PLUMBING
J 2
(4350 4700);
DISPLAY 1.234043 (4350 4700);
PAINT GREEN (4350 4700);
DISPLAY INVISIBLE (4350 4700);
FORCEPROP 1 LAST HDL_TAP TRUE
J 2
(4025 4625);
DISPLAY 1.234043 (4025 4625);
PAINT GREEN (4025 4625);
DISPLAY INVISIBLE (4025 4625);
FORCEPROP 1 LAST PATH I4
J 2
(4352 4750);
DISPLAY 0.872340 (4352 4750);
PAINT GREEN (4352 4750);
DISPLAY INVISIBLE (4352 4750);
FORCEADD TAP..6
R 2
(4100 3100);
FORCEPROP 3 LASTPIN (4050 3100) SIG_NAME M_D_DQS_DP<0>
J 0
(4060 3110);
DISPLAY 0.659574 (4060 3110);
PAINT MONO (4060 3110);
DISPLAY INVISIBLE (4060 3110);
FORCEPROP 1 LASTPIN (4050 3100) BN 0
J 2
(4100 3110);
DISPLAY 0.617021 (4100 3110);
PAINT PINK (4100 3110);
FORCEPROP 2 LAST CDS_LIB mstr_standard
J 0
(4100 3100);
DISPLAY 0.787234 (4100 3100);
PAINT MONO (4100 3100);
DISPLAY INVISIBLE (4100 3100);
FORCEPROP 1 LAST BODY_TYPE PLUMBING
J 2
(4100 3050);
DISPLAY 1.234043 (4100 3050);
PAINT GREEN (4100 3050);
DISPLAY INVISIBLE (4100 3050);
FORCEPROP 1 LAST HDL_TAP TRUE
J 2
(3775 2975);
DISPLAY 1.234043 (3775 2975);
PAINT GREEN (3775 2975);
DISPLAY INVISIBLE (3775 2975);
FORCEPROP 1 LAST PATH I40
J 2
(4102 3100);
DISPLAY 0.872340 (4102 3100);
PAINT GREEN (4102 3100);
DISPLAY INVISIBLE (4102 3100);
FORCEADD SCONN288_H44441003..3
(5250 2050);
FORCEPROP 1 LAST LOCATION J6M1
J 0
(4800 3450);
DISPLAY 0.617021 (4800 3450);
PAINT AQUA (4800 3450);
FORCEPROP 1 LAST PART_NUMBER H44441-003
J 0
(4800 700);
DISPLAY 0.617021 (4800 700);
PAINT BLUE (4800 700);
FORCEPROP 1 LAST MATERIAL SCONN
J 0
(4800 3400);
DISPLAY 0.617021 (4800 3400);
PAINT SKYBLUE (4800 3400);
FORCEPROP 2 LASTPIN (4750 3200) $PN 2
J 2
(4740 3210);
DISPLAY 0.617021 (4740 3210);
PAINT ORANGE (4740 3210);
FORCEPROP 2 LASTPIN (4750 3150) $PN 4
J 2
(4740 3160);
DISPLAY 0.617021 (4740 3160);
PAINT ORANGE (4740 3160);
FORCEPROP 2 LASTPIN (4750 3100) $PN 6
J 2
(4740 3110);
DISPLAY 0.617021 (4740 3110);
PAINT ORANGE (4740 3110);
FORCEPROP 2 LASTPIN (4750 3050) $PN 9
J 2
(4740 3060);
DISPLAY 0.617021 (4740 3060);
PAINT ORANGE (4740 3060);
FORCEPROP 2 LASTPIN (4750 3000) $PN 11
J 2
(4740 3010);
DISPLAY 0.617021 (4740 3010);
PAINT ORANGE (4740 3010);
FORCEPROP 2 LASTPIN (4750 2950) $PN 13
J 2
(4740 2960);
DISPLAY 0.617021 (4740 2960);
PAINT ORANGE (4740 2960);
FORCEPROP 2 LASTPIN (4750 2900) $PN 15
J 2
(4740 2910);
DISPLAY 0.617021 (4740 2910);
PAINT ORANGE (4740 2910);
FORCEPROP 2 LASTPIN (4750 2850) $PN 17
J 2
(4740 2860);
DISPLAY 0.617021 (4740 2860);
PAINT ORANGE (4740 2860);
FORCEPROP 2 LASTPIN (4750 2800) $PN 20
J 2
(4740 2810);
DISPLAY 0.617021 (4740 2810);
PAINT ORANGE (4740 2810);
FORCEPROP 2 LASTPIN (4750 2750) $PN 22
J 2
(4740 2760);
DISPLAY 0.617021 (4740 2760);
PAINT ORANGE (4740 2760);
FORCEPROP 2 LASTPIN (4750 2700) $PN 24
J 2
(4740 2710);
DISPLAY 0.617021 (4740 2710);
PAINT ORANGE (4740 2710);
FORCEPROP 2 LASTPIN (4750 2650) $PN 26
J 2
(4740 2660);
DISPLAY 0.617021 (4740 2660);
PAINT ORANGE (4740 2660);
FORCEPROP 2 LASTPIN (4750 2600) $PN 28
J 2
(4740 2610);
DISPLAY 0.617021 (4740 2610);
PAINT ORANGE (4740 2610);
FORCEPROP 2 LASTPIN (4750 2550) $PN 31
J 2
(4740 2560);
DISPLAY 0.617021 (4740 2560);
PAINT ORANGE (4740 2560);
FORCEPROP 2 LASTPIN (4750 2500) $PN 33
J 2
(4740 2510);
DISPLAY 0.617021 (4740 2510);
PAINT ORANGE (4740 2510);
FORCEPROP 2 LASTPIN (4750 2450) $PN 35
J 2
(4740 2460);
DISPLAY 0.617021 (4740 2460);
PAINT ORANGE (4740 2460);
FORCEPROP 2 LASTPIN (4750 2400) $PN 37
J 2
(4740 2410);
DISPLAY 0.617021 (4740 2410);
PAINT ORANGE (4740 2410);
FORCEPROP 2 LASTPIN (4750 2350) $PN 39
J 2
(4740 2360);
DISPLAY 0.617021 (4740 2360);
PAINT ORANGE (4740 2360);
FORCEPROP 2 LASTPIN (4750 2300) $PN 42
J 2
(4740 2310);
DISPLAY 0.617021 (4740 2310);
PAINT ORANGE (4740 2310);
FORCEPROP 2 LASTPIN (4750 2250) $PN 44
J 2
(4740 2260);
DISPLAY 0.617021 (4740 2260);
PAINT ORANGE (4740 2260);
FORCEPROP 2 LASTPIN (4750 2200) $PN 46
J 2
(4740 2210);
DISPLAY 0.617021 (4740 2210);
PAINT ORANGE (4740 2210);
FORCEPROP 2 LASTPIN (4750 2150) $PN 48
J 2
(4740 2160);
DISPLAY 0.617021 (4740 2160);
PAINT ORANGE (4740 2160);
FORCEPROP 2 LASTPIN (4750 2100) $PN 50
J 2
(4740 2110);
DISPLAY 0.617021 (4740 2110);
PAINT ORANGE (4740 2110);
FORCEPROP 2 LASTPIN (4750 2050) $PN 53
J 2
(4740 2060);
DISPLAY 0.617021 (4740 2060);
PAINT ORANGE (4740 2060);
FORCEPROP 2 LASTPIN (4750 2000) $PN 55
J 2
(4740 2010);
DISPLAY 0.617021 (4740 2010);
PAINT ORANGE (4740 2010);
FORCEPROP 2 LASTPIN (4750 1950) $PN 57
J 2
(4740 1960);
DISPLAY 0.617021 (4740 1960);
PAINT ORANGE (4740 1960);
FORCEPROP 2 LASTPIN (4750 1900) $PN 94
J 2
(4740 1910);
DISPLAY 0.617021 (4740 1910);
PAINT ORANGE (4740 1910);
FORCEPROP 2 LASTPIN (4750 1850) $PN 96
J 2
(4740 1860);
DISPLAY 0.617021 (4740 1860);
PAINT ORANGE (4740 1860);
FORCEPROP 2 LASTPIN (4750 1800) $PN 98
J 2
(4740 1810);
DISPLAY 0.617021 (4740 1810);
PAINT ORANGE (4740 1810);
FORCEPROP 2 LASTPIN (4750 1750) $PN 101
J 2
(4740 1760);
DISPLAY 0.617021 (4740 1760);
PAINT ORANGE (4740 1760);
FORCEPROP 2 LASTPIN (4750 1700) $PN 103
J 2
(4740 1710);
DISPLAY 0.617021 (4740 1710);
PAINT ORANGE (4740 1710);
FORCEPROP 2 LASTPIN (4750 1650) $PN 105
J 2
(4740 1660);
DISPLAY 0.617021 (4740 1660);
PAINT ORANGE (4740 1660);
FORCEPROP 2 LASTPIN (4750 1600) $PN 107
J 2
(4740 1610);
DISPLAY 0.617021 (4740 1610);
PAINT ORANGE (4740 1610);
FORCEPROP 2 LASTPIN (4750 1550) $PN 109
J 2
(4740 1560);
DISPLAY 0.617021 (4740 1560);
PAINT ORANGE (4740 1560);
FORCEPROP 2 LASTPIN (4750 1500) $PN 112
J 2
(4740 1510);
DISPLAY 0.617021 (4740 1510);
PAINT ORANGE (4740 1510);
FORCEPROP 2 LASTPIN (4750 1450) $PN 114
J 2
(4740 1460);
DISPLAY 0.617021 (4740 1460);
PAINT ORANGE (4740 1460);
FORCEPROP 2 LASTPIN (4750 1400) $PN 116
J 2
(4740 1410);
DISPLAY 0.617021 (4740 1410);
PAINT ORANGE (4740 1410);
FORCEPROP 2 LASTPIN (4750 1350) $PN 118
J 2
(4740 1360);
DISPLAY 0.617021 (4740 1360);
PAINT ORANGE (4740 1360);
FORCEPROP 2 LASTPIN (4750 1300) $PN 120
J 2
(4740 1310);
DISPLAY 0.617021 (4740 1310);
PAINT ORANGE (4740 1310);
FORCEPROP 2 LASTPIN (4750 1250) $PN 123
J 2
(4740 1260);
DISPLAY 0.617021 (4740 1260);
PAINT ORANGE (4740 1260);
FORCEPROP 2 LASTPIN (4750 1200) $PN 125
J 2
(4740 1210);
DISPLAY 0.617021 (4740 1210);
PAINT ORANGE (4740 1210);
FORCEPROP 2 LASTPIN (4750 1150) $PN 127
J 2
(4740 1160);
DISPLAY 0.617021 (4740 1160);
PAINT ORANGE (4740 1160);
FORCEPROP 2 LASTPIN (4750 1100) $PN 129
J 2
(4740 1110);
DISPLAY 0.617021 (4740 1110);
PAINT ORANGE (4740 1110);
FORCEPROP 2 LASTPIN (4750 1050) $PN 131
J 2
(4740 1060);
DISPLAY 0.617021 (4740 1060);
PAINT ORANGE (4740 1060);
FORCEPROP 2 LASTPIN (4750 1000) $PN 134
J 2
(4740 1010);
DISPLAY 0.617021 (4740 1010);
PAINT ORANGE (4740 1010);
FORCEPROP 2 LASTPIN (4750 950) $PN 136
J 2
(4740 960);
DISPLAY 0.617021 (4740 960);
PAINT ORANGE (4740 960);
FORCEPROP 2 LASTPIN (4750 900) $PN 138
J 2
(4740 910);
DISPLAY 0.617021 (4740 910);
PAINT ORANGE (4740 910);
FORCEPROP 2 LASTPIN (5750 3200) $PN 147
J 0
(5760 3210);
DISPLAY 0.617021 (5760 3210);
PAINT ORANGE (5760 3210);
FORCEPROP 2 LASTPIN (5750 3150) $PN 149
J 0
(5760 3160);
DISPLAY 0.617021 (5760 3160);
PAINT ORANGE (5760 3160);
FORCEPROP 2 LASTPIN (5750 3100) $PN 151
J 0
(5760 3110);
DISPLAY 0.617021 (5760 3110);
PAINT ORANGE (5760 3110);
FORCEPROP 2 LASTPIN (5750 3050) $PN 154
J 0
(5760 3060);
DISPLAY 0.617021 (5760 3060);
PAINT ORANGE (5760 3060);
FORCEPROP 2 LASTPIN (5750 3000) $PN 156
J 0
(5760 3010);
DISPLAY 0.617021 (5760 3010);
PAINT ORANGE (5760 3010);
FORCEPROP 2 LASTPIN (5750 2950) $PN 158
J 0
(5760 2960);
DISPLAY 0.617021 (5760 2960);
PAINT ORANGE (5760 2960);
FORCEPROP 2 LASTPIN (5750 2900) $PN 160
J 0
(5760 2910);
DISPLAY 0.617021 (5760 2910);
PAINT ORANGE (5760 2910);
FORCEPROP 2 LASTPIN (5750 2850) $PN 162
J 0
(5760 2860);
DISPLAY 0.617021 (5760 2860);
PAINT ORANGE (5760 2860);
FORCEPROP 2 LASTPIN (5750 2800) $PN 165
J 0
(5760 2810);
DISPLAY 0.617021 (5760 2810);
PAINT ORANGE (5760 2810);
FORCEPROP 2 LASTPIN (5750 2750) $PN 167
J 0
(5760 2760);
DISPLAY 0.617021 (5760 2760);
PAINT ORANGE (5760 2760);
FORCEPROP 2 LASTPIN (5750 2700) $PN 169
J 0
(5760 2710);
DISPLAY 0.617021 (5760 2710);
PAINT ORANGE (5760 2710);
FORCEPROP 2 LASTPIN (5750 2650) $PN 171
J 0
(5760 2660);
DISPLAY 0.617021 (5760 2660);
PAINT ORANGE (5760 2660);
FORCEPROP 2 LASTPIN (5750 2600) $PN 173
J 0
(5760 2610);
DISPLAY 0.617021 (5760 2610);
PAINT ORANGE (5760 2610);
FORCEPROP 2 LASTPIN (5750 2550) $PN 176
J 0
(5760 2560);
DISPLAY 0.617021 (5760 2560);
PAINT ORANGE (5760 2560);
FORCEPROP 2 LASTPIN (5750 2500) $PN 178
J 0
(5760 2510);
DISPLAY 0.617021 (5760 2510);
PAINT ORANGE (5760 2510);
FORCEPROP 2 LASTPIN (5750 2450) $PN 180
J 0
(5760 2460);
DISPLAY 0.617021 (5760 2460);
PAINT ORANGE (5760 2460);
FORCEPROP 2 LASTPIN (5750 2400) $PN 182
J 0
(5760 2410);
DISPLAY 0.617021 (5760 2410);
PAINT ORANGE (5760 2410);
FORCEPROP 2 LASTPIN (5750 2350) $PN 184
J 0
(5760 2360);
DISPLAY 0.617021 (5760 2360);
PAINT ORANGE (5760 2360);
FORCEPROP 2 LASTPIN (5750 2300) $PN 187
J 0
(5760 2310);
DISPLAY 0.617021 (5760 2310);
PAINT ORANGE (5760 2310);
FORCEPROP 2 LASTPIN (5750 2250) $PN 189
J 0
(5760 2260);
DISPLAY 0.617021 (5760 2260);
PAINT ORANGE (5760 2260);
FORCEPROP 2 LASTPIN (5750 2200) $PN 191
J 0
(5760 2210);
DISPLAY 0.617021 (5760 2210);
PAINT ORANGE (5760 2210);
FORCEPROP 2 LASTPIN (5750 2150) $PN 193
J 0
(5760 2160);
DISPLAY 0.617021 (5760 2160);
PAINT ORANGE (5760 2160);
FORCEPROP 2 LASTPIN (5750 2100) $PN 195
J 0
(5760 2110);
DISPLAY 0.617021 (5760 2110);
PAINT ORANGE (5760 2110);
FORCEPROP 2 LASTPIN (5750 2050) $PN 198
J 0
(5760 2060);
DISPLAY 0.617021 (5760 2060);
PAINT ORANGE (5760 2060);
FORCEPROP 2 LASTPIN (5750 2000) $PN 200
J 0
(5760 2010);
DISPLAY 0.617021 (5760 2010);
PAINT ORANGE (5760 2010);
FORCEPROP 2 LASTPIN (5750 1950) $PN 202
J 0
(5760 1960);
DISPLAY 0.617021 (5760 1960);
PAINT ORANGE (5760 1960);
FORCEPROP 2 LASTPIN (5750 1900) $PN 239
J 0
(5760 1910);
DISPLAY 0.617021 (5760 1910);
PAINT ORANGE (5760 1910);
FORCEPROP 2 LASTPIN (5750 1850) $PN 241
J 0
(5760 1860);
DISPLAY 0.617021 (5760 1860);
PAINT ORANGE (5760 1860);
FORCEPROP 2 LASTPIN (5750 1800) $PN 243
J 0
(5760 1810);
DISPLAY 0.617021 (5760 1810);
PAINT ORANGE (5760 1810);
FORCEPROP 2 LASTPIN (5750 1750) $PN 246
J 0
(5760 1760);
DISPLAY 0.617021 (5760 1760);
PAINT ORANGE (5760 1760);
FORCEPROP 2 LASTPIN (5750 1700) $PN 248
J 0
(5760 1710);
DISPLAY 0.617021 (5760 1710);
PAINT ORANGE (5760 1710);
FORCEPROP 2 LASTPIN (5750 1650) $PN 250
J 0
(5760 1660);
DISPLAY 0.617021 (5760 1660);
PAINT ORANGE (5760 1660);
FORCEPROP 2 LASTPIN (5750 1600) $PN 252
J 0
(5760 1610);
DISPLAY 0.617021 (5760 1610);
PAINT ORANGE (5760 1610);
FORCEPROP 2 LASTPIN (5750 1550) $PN 254
J 0
(5760 1560);
DISPLAY 0.617021 (5760 1560);
PAINT ORANGE (5760 1560);
FORCEPROP 2 LASTPIN (5750 1500) $PN 257
J 0
(5760 1510);
DISPLAY 0.617021 (5760 1510);
PAINT ORANGE (5760 1510);
FORCEPROP 2 LASTPIN (5750 1450) $PN 259
J 0
(5760 1460);
DISPLAY 0.617021 (5760 1460);
PAINT ORANGE (5760 1460);
FORCEPROP 2 LASTPIN (5750 1400) $PN 261
J 0
(5760 1410);
DISPLAY 0.617021 (5760 1410);
PAINT ORANGE (5760 1410);
FORCEPROP 2 LASTPIN (5750 1350) $PN 263
J 0
(5760 1360);
DISPLAY 0.617021 (5760 1360);
PAINT ORANGE (5760 1360);
FORCEPROP 2 LASTPIN (5750 1300) $PN 265
J 0
(5760 1310);
DISPLAY 0.617021 (5760 1310);
PAINT ORANGE (5760 1310);
FORCEPROP 2 LASTPIN (5750 1250) $PN 268
J 0
(5760 1260);
DISPLAY 0.617021 (5760 1260);
PAINT ORANGE (5760 1260);
FORCEPROP 2 LASTPIN (5750 1200) $PN 270
J 0
(5760 1210);
DISPLAY 0.617021 (5760 1210);
PAINT ORANGE (5760 1210);
FORCEPROP 2 LASTPIN (5750 1150) $PN 272
J 0
(5760 1160);
DISPLAY 0.617021 (5760 1160);
PAINT ORANGE (5760 1160);
FORCEPROP 2 LASTPIN (5750 1100) $PN 274
J 0
(5760 1110);
DISPLAY 0.617021 (5760 1110);
PAINT ORANGE (5760 1110);
FORCEPROP 2 LASTPIN (5750 1050) $PN 276
J 0
(5760 1060);
DISPLAY 0.617021 (5760 1060);
PAINT ORANGE (5760 1060);
FORCEPROP 2 LASTPIN (5750 1000) $PN 279
J 0
(5760 1010);
DISPLAY 0.617021 (5760 1010);
PAINT ORANGE (5760 1010);
FORCEPROP 2 LASTPIN (5750 950) $PN 281
J 0
(5760 960);
DISPLAY 0.617021 (5760 960);
PAINT ORANGE (5760 960);
FORCEPROP 2 LASTPIN (5750 900) $PN 283
J 0
(5760 910);
DISPLAY 0.617021 (5760 910);
PAINT ORANGE (5760 910);
FORCEPROP 1 LAST PACK_TYPE PIP
J 0
(4800 3500);
PAINT SKYBLUE (4800 3500);
DISPLAY INVISIBLE (4800 3500);
FORCEPROP 2 LAST BOM_COST MEM
J 0
(5250 2050);
PAINT ORANGE (5250 2050);
DISPLAY INVISIBLE (5250 2050);
FORCEPROP 2 LAST CDS_LIB mstr_sconn
J 0
(5250 2050);
PAINT ORANGE (5250 2050);
DISPLAY INVISIBLE (5250 2050);
FORCEPROP 2 LAST SEC_TYPE PIP
J 0
(4800 3500);
DISPLAY 1.021277 (4800 3500);
PAINT ORANGE (4800 3500);
DISPLAY INVISIBLE (4800 3500);
FORCEPROP 2 LAST SEC 3
J 0
(4800 3500);
DISPLAY 0.680851 (4800 3500);
PAINT MONO (4800 3500);
DISPLAY INVISIBLE (4800 3500);
FORCEPROP 2 LAST CDS_LOCATION J6M1
J 0
(4800 3450);
DISPLAY 0.617021 (4800 3450);
PAINT AQUA (4800 3450);
DISPLAY INVISIBLE (4800 3450);
FORCEPROP 1 LAST PATH I44
J 0
(5250 3400);
PAINT GREEN (5250 3400);
DISPLAY INVISIBLE (5250 3400);
FORCEPROP 2 LAST ROOM DDR4_CH_D
J 0
(5250 2050);
PAINT ORANGE (5250 2050);
DISPLAY INVISIBLE (5250 2050);
FORCEADD GND..1
R 2
(4550 750);
FORCEPROP 3 LASTPIN (4550 800) SIG_NAME GND\g
J 0
(4560 810);
DISPLAY 0.659574 (4560 810);
PAINT MONO (4560 810);
DISPLAY INVISIBLE (4560 810);
FORCEPROP 1 LAST VOLTAGE 0
J 0
(4550 750);
PAINT SKYBLUE (4550 750);
DISPLAY INVISIBLE (4550 750);
FORCEPROP 2 LAST BOM_COST MEM
J 0
(4550 755);
PAINT ORANGE (4550 755);
DISPLAY INVISIBLE (4550 755);
FORCEPROP 2 LAST CDS_LIB mstr_symbols
J 0
(4550 750);
DISPLAY 0.787234 (4550 750);
PAINT MONO (4550 750);
DISPLAY INVISIBLE (4550 750);
FORCEPROP 1 LAST SIZE 1B
J 2
(4475 700);
DISPLAY 1.170213 (4475 700);
PAINT GREEN (4475 700);
DISPLAY INVISIBLE (4475 700);
FORCEPROP 1 LAST BODY_TYPE PLUMBING
J 2
(4595 707);
DISPLAY 0.340426 (4595 707);
PAINT GREEN (4595 707);
DISPLAY INVISIBLE (4595 707);
FORCEPROP 1 LAST PATH I45
J 2
(4475 750);
DISPLAY 0.872340 (4475 750);
PAINT AQUA (4475 750);
DISPLAY INVISIBLE (4475 750);
FORCEPROP 2 LAST ROOM DDR4_CH_B
J 0
(4550 755);
PAINT ORANGE (4550 755);
DISPLAY INVISIBLE (4550 755);
FORCEPROP 1 LAST HDL_POWER GND
J 2
(4550 900);
DISPLAY 0.553191 (4550 900);
PAINT GREEN (4550 900);
DISPLAY INVISIBLE (4550 900);
FORCEADD SCONN288_H44441003..2
(3400 3950);
FORCEPROP 1 LAST LOCATION J6M1
J 0
(3000 5050);
DISPLAY 0.617021 (3000 5050);
PAINT AQUA (3000 5050);
FORCEPROP 1 LAST PART_NUMBER H44441-003
J 0
(3000 2850);
DISPLAY 0.617021 (3000 2850);
PAINT BLUE (3000 2850);
FORCEPROP 1 LAST MATERIAL SCONN
J 0
(3000 5000);
DISPLAY 0.617021 (3000 5000);
PAINT SKYBLUE (3000 5000);
FORCEPROP 2 LASTPIN (3850 4800) $PN 51
J 0
(3860 4810);
DISPLAY 0.617021 (3860 4810);
PAINT ORANGE (3860 4810);
FORCEPROP 2 LASTPIN (3850 4750) $PN 52
J 0
(3860 4760);
DISPLAY 0.617021 (3860 4760);
PAINT ORANGE (3860 4760);
FORCEPROP 2 LASTPIN (3850 4700) $PN 132
J 0
(3860 4710);
DISPLAY 0.617021 (3860 4710);
PAINT ORANGE (3860 4710);
FORCEPROP 2 LASTPIN (3850 4650) $PN 133
J 0
(3860 4660);
DISPLAY 0.617021 (3860 4660);
PAINT ORANGE (3860 4660);
FORCEPROP 2 LASTPIN (3850 4600) $PN 121
J 0
(3860 4610);
DISPLAY 0.617021 (3860 4610);
PAINT ORANGE (3860 4610);
FORCEPROP 2 LASTPIN (3850 4550) $PN 122
J 0
(3860 4560);
DISPLAY 0.617021 (3860 4560);
PAINT ORANGE (3860 4560);
FORCEPROP 2 LASTPIN (3850 4500) $PN 110
J 0
(3860 4510);
DISPLAY 0.617021 (3860 4510);
PAINT ORANGE (3860 4510);
FORCEPROP 2 LASTPIN (3850 4450) $PN 111
J 0
(3860 4460);
DISPLAY 0.617021 (3860 4460);
PAINT ORANGE (3860 4460);
FORCEPROP 2 LASTPIN (3850 4400) $PN 99
J 0
(3860 4410);
DISPLAY 0.617021 (3860 4410);
PAINT ORANGE (3860 4410);
FORCEPROP 2 LASTPIN (3850 4350) $PN 100
J 0
(3860 4360);
DISPLAY 0.617021 (3860 4360);
PAINT ORANGE (3860 4360);
FORCEPROP 2 LASTPIN (3850 4300) $PN 40
J 0
(3860 4310);
DISPLAY 0.617021 (3860 4310);
PAINT ORANGE (3860 4310);
FORCEPROP 2 LASTPIN (3850 4250) $PN 41
J 0
(3860 4260);
DISPLAY 0.617021 (3860 4260);
PAINT ORANGE (3860 4260);
FORCEPROP 2 LASTPIN (3850 4200) $PN 29
J 0
(3860 4210);
DISPLAY 0.617021 (3860 4210);
PAINT ORANGE (3860 4210);
FORCEPROP 2 LASTPIN (3850 4150) $PN 30
J 0
(3860 4160);
DISPLAY 0.617021 (3860 4160);
PAINT ORANGE (3860 4160);
FORCEPROP 2 LASTPIN (3850 4100) $PN 18
J 0
(3860 4110);
DISPLAY 0.617021 (3860 4110);
PAINT ORANGE (3860 4110);
FORCEPROP 2 LASTPIN (3850 4050) $PN 19
J 0
(3860 4060);
DISPLAY 0.617021 (3860 4060);
PAINT ORANGE (3860 4060);
FORCEPROP 2 LASTPIN (3850 4000) $PN 7
J 0
(3860 4010);
DISPLAY 0.617021 (3860 4010);
PAINT ORANGE (3860 4010);
FORCEPROP 2 LASTPIN (3850 3950) $PN 8
J 0
(3860 3960);
DISPLAY 0.617021 (3860 3960);
PAINT ORANGE (3860 3960);
FORCEPROP 2 LASTPIN (3850 3900) $PN 197
J 0
(3860 3910);
DISPLAY 0.617021 (3860 3910);
PAINT ORANGE (3860 3910);
FORCEPROP 2 LASTPIN (3850 3850) $PN 196
J 0
(3860 3860);
DISPLAY 0.617021 (3860 3860);
PAINT ORANGE (3860 3860);
FORCEPROP 2 LASTPIN (3850 3800) $PN 278
J 0
(3860 3810);
DISPLAY 0.617021 (3860 3810);
PAINT ORANGE (3860 3810);
FORCEPROP 2 LASTPIN (3850 3750) $PN 277
J 0
(3860 3760);
DISPLAY 0.617021 (3860 3760);
PAINT ORANGE (3860 3760);
FORCEPROP 2 LASTPIN (3850 3700) $PN 267
J 0
(3860 3710);
DISPLAY 0.617021 (3860 3710);
PAINT ORANGE (3860 3710);
FORCEPROP 2 LASTPIN (3850 3650) $PN 266
J 0
(3860 3660);
DISPLAY 0.617021 (3860 3660);
PAINT ORANGE (3860 3660);
FORCEPROP 2 LASTPIN (3850 3600) $PN 256
J 0
(3860 3610);
DISPLAY 0.617021 (3860 3610);
PAINT ORANGE (3860 3610);
FORCEPROP 2 LASTPIN (3850 3550) $PN 255
J 0
(3860 3560);
DISPLAY 0.617021 (3860 3560);
PAINT ORANGE (3860 3560);
FORCEPROP 2 LASTPIN (3850 3500) $PN 245
J 0
(3860 3510);
DISPLAY 0.617021 (3860 3510);
PAINT ORANGE (3860 3510);
FORCEPROP 2 LASTPIN (3850 3450) $PN 244
J 0
(3860 3460);
DISPLAY 0.617021 (3860 3460);
PAINT ORANGE (3860 3460);
FORCEPROP 2 LASTPIN (3850 3400) $PN 186
J 0
(3860 3410);
DISPLAY 0.617021 (3860 3410);
PAINT ORANGE (3860 3410);
FORCEPROP 2 LASTPIN (3850 3350) $PN 185
J 0
(3860 3360);
DISPLAY 0.617021 (3860 3360);
PAINT ORANGE (3860 3360);
FORCEPROP 2 LASTPIN (3850 3300) $PN 175
J 0
(3860 3310);
DISPLAY 0.617021 (3860 3310);
PAINT ORANGE (3860 3310);
FORCEPROP 2 LASTPIN (3850 3250) $PN 174
J 0
(3860 3260);
DISPLAY 0.617021 (3860 3260);
PAINT ORANGE (3860 3260);
FORCEPROP 2 LASTPIN (3850 3200) $PN 164
J 0
(3860 3210);
DISPLAY 0.617021 (3860 3210);
PAINT ORANGE (3860 3210);
FORCEPROP 2 LASTPIN (3850 3150) $PN 163
J 0
(3860 3160);
DISPLAY 0.617021 (3860 3160);
PAINT ORANGE (3860 3160);
FORCEPROP 2 LASTPIN (3850 3100) $PN 153
J 0
(3860 3110);
DISPLAY 0.617021 (3860 3110);
PAINT ORANGE (3860 3110);
FORCEPROP 2 LASTPIN (3850 3050) $PN 152
J 0
(3860 3060);
DISPLAY 0.617021 (3860 3060);
PAINT ORANGE (3860 3060);
FORCEPROP 1 LAST PACK_TYPE PIP
J 0
(3000 5100);
PAINT SKYBLUE (3000 5100);
DISPLAY INVISIBLE (3000 5100);
FORCEPROP 2 LAST BOM_COST MEM
J 0
(3400 3950);
PAINT ORANGE (3400 3950);
DISPLAY INVISIBLE (3400 3950);
FORCEPROP 2 LAST CDS_LIB mstr_sconn
J 0
(3400 3950);
PAINT ORANGE (3400 3950);
DISPLAY INVISIBLE (3400 3950);
FORCEPROP 2 LAST SEC_TYPE PIP
J 0
(3000 5100);
DISPLAY 1.021277 (3000 5100);
PAINT ORANGE (3000 5100);
DISPLAY INVISIBLE (3000 5100);
FORCEPROP 2 LAST SEC 2
J 0
(3000 5100);
DISPLAY 0.680851 (3000 5100);
PAINT MONO (3000 5100);
DISPLAY INVISIBLE (3000 5100);
FORCEPROP 2 LAST CDS_LOCATION J6M1
J 0
(3000 5050);
DISPLAY 0.617021 (3000 5050);
PAINT AQUA (3000 5050);
DISPLAY INVISIBLE (3000 5050);
FORCEPROP 1 LAST PATH I46
J 0
(3400 5000);
PAINT GREEN (3400 5000);
DISPLAY INVISIBLE (3400 5000);
FORCEPROP 2 LAST ROOM DDR4_CH_D
J 0
(3400 3950);
PAINT ORANGE (3400 3950);
DISPLAY INVISIBLE (3400 3950);
FORCEADD PVPP_DEF..1
(2700 2550);
FORCEPROP 3 LASTPIN (2700 2500) SIG_NAME PVPP_DEF\g
J 0
(2710 2510);
DISPLAY 0.659574 (2710 2510);
PAINT MONO (2710 2510);
DISPLAY INVISIBLE (2710 2510);
FORCEPROP 1 LAST VOLTAGE 2.5V
J 0
(2655 2507);
DISPLAY 0.340426 (2655 2507);
PAINT SKYBLUE (2655 2507);
DISPLAY INVISIBLE (2655 2507);
FORCEPROP 0 LAST BOM_COST MEM
J 0
(2700 2650);
PAINT ORANGE (2700 2650);
DISPLAY INVISIBLE (2700 2650);
FORCEPROP 2 LAST CDS_LIB mstr_symbols
J 0
(2700 2550);
PAINT ORANGE (2700 2550);
DISPLAY INVISIBLE (2700 2550);
FORCEPROP 1 LAST BODY_TYPE PLUMBING
J 0
(2655 2507);
DISPLAY 0.340426 (2655 2507);
PAINT GREEN (2655 2507);
DISPLAY INVISIBLE (2655 2507);
FORCEPROP 1 LAST PATH I47
J 0
(2750 2575);
DISPLAY 0.872340 (2750 2575);
PAINT AQUA (2750 2575);
DISPLAY INVISIBLE (2750 2575);
FORCEPROP 2 LAST ROOM DDR4_CH_B
J 0
(2700 2650);
PAINT ORANGE (2700 2650);
DISPLAY INVISIBLE (2700 2650);
FORCEPROP 1 LAST HDL_POWER PVPP_DEF
J 1
(2700 2600);
DISPLAY 0.872340 (2700 2600);
PAINT GREEN (2700 2600);
DISPLAY INVISIBLE (2700 2600);
FORCEADD PVTT_DEF..1
(2550 2250);
FORCEPROP 3 LASTPIN (2550 2200) SIG_NAME PVTT_DEF\g
J 0
(2560 2210);
DISPLAY 0.659574 (2560 2210);
PAINT MONO (2560 2210);
DISPLAY INVISIBLE (2560 2210);
FORCEPROP 1 LAST VOLTAGE 0.6V
J 0
(2505 2207);
DISPLAY 0.340426 (2505 2207);
PAINT SKYBLUE (2505 2207);
DISPLAY INVISIBLE (2505 2207);
FORCEPROP 2 LAST BOM_COST MEM
J 0
(2550 2255);
PAINT ORANGE (2550 2255);
DISPLAY INVISIBLE (2550 2255);
FORCEPROP 2 LAST CDS_LIB mstr_symbols
J 0
(2550 2250);
PAINT ORANGE (2550 2250);
DISPLAY INVISIBLE (2550 2250);
FORCEPROP 1 LAST BODY_TYPE PLUMBING
J 0
(2505 2207);
DISPLAY 0.340426 (2505 2207);
PAINT GREEN (2505 2207);
DISPLAY INVISIBLE (2505 2207);
FORCEPROP 1 LAST PATH I48
J 0
(2600 2275);
DISPLAY 0.872340 (2600 2275);
PAINT AQUA (2600 2275);
DISPLAY INVISIBLE (2600 2275);
FORCEPROP 2 LAST ROOM DDR4_CH_B
J 0
(2550 2350);
DISPLAY 0.787234 (2550 2350);
PAINT ORANGE (2550 2350);
DISPLAY INVISIBLE (2550 2350);
FORCEPROP 1 LAST HDL_POWER PVTT_DEF
J 1
(2550 2300);
DISPLAY 0.872340 (2550 2300);
PAINT GREEN (2550 2300);
DISPLAY INVISIBLE (2550 2300);
FORCEADD PVDDQ_DEF..1
(2300 2100);
FORCEPROP 3 LASTPIN (2300 2050) SIG_NAME PVDDQ_DEF\g
J 0
(2310 2060);
DISPLAY 0.659574 (2310 2060);
PAINT MONO (2310 2060);
DISPLAY INVISIBLE (2310 2060);
FORCEPROP 1 LAST VOLTAGE 1.2V
J 0
(2255 2057);
DISPLAY 0.340426 (2255 2057);
PAINT SKYBLUE (2255 2057);
DISPLAY INVISIBLE (2255 2057);
FORCEPROP 2 LAST BOM_COST MEM
J 0
(2300 2105);
PAINT ORANGE (2300 2105);
DISPLAY INVISIBLE (2300 2105);
FORCEPROP 2 LAST CDS_LIB mstr_symbols
J 0
(2300 2100);
PAINT ORANGE (2300 2100);
DISPLAY INVISIBLE (2300 2100);
FORCEPROP 1 LAST BODY_TYPE PLUMBING
J 0
(2255 2057);
DISPLAY 0.340426 (2255 2057);
PAINT GREEN (2255 2057);
DISPLAY INVISIBLE (2255 2057);
FORCEPROP 1 LAST PATH I49
J 0
(2350 2125);
DISPLAY 0.872340 (2350 2125);
PAINT AQUA (2350 2125);
DISPLAY INVISIBLE (2350 2125);
FORCEPROP 2 LAST ROOM DDR4_CH_B
J 0
(2300 2200);
DISPLAY 0.787234 (2300 2200);
PAINT ORANGE (2300 2200);
DISPLAY INVISIBLE (2300 2200);
FORCEPROP 1 LAST HDL_POWER PVDDQ_DEF
J 1
(2300 2150);
DISPLAY 0.872340 (2300 2150);
PAINT GREEN (2300 2150);
DISPLAY INVISIBLE (2300 2150);
FORCEADD TAP..6
R 2
(4350 4650);
FORCEPROP 3 LASTPIN (4300 4650) SIG_NAME M_D_DQS_DN<16>
J 0
(4310 4660);
DISPLAY 0.659574 (4310 4660);
PAINT MONO (4310 4660);
DISPLAY INVISIBLE (4310 4660);
FORCEPROP 1 LASTPIN (4300 4650) BN 16
J 2
(4350 4660);
DISPLAY 0.617021 (4350 4660);
PAINT PINK (4350 4660);
FORCEPROP 2 LAST CDS_LIB mstr_standard
J 0
(4350 4650);
DISPLAY 0.787234 (4350 4650);
PAINT MONO (4350 4650);
DISPLAY INVISIBLE (4350 4650);
FORCEPROP 1 LAST BODY_TYPE PLUMBING
J 2
(4350 4600);
DISPLAY 1.234043 (4350 4600);
PAINT GREEN (4350 4600);
DISPLAY INVISIBLE (4350 4600);
FORCEPROP 1 LAST HDL_TAP TRUE
J 2
(4025 4525);
DISPLAY 1.234043 (4025 4525);
PAINT GREEN (4025 4525);
DISPLAY INVISIBLE (4025 4525);
FORCEPROP 1 LAST PATH I5
J 2
(4352 4650);
DISPLAY 0.872340 (4352 4650);
PAINT GREEN (4352 4650);
DISPLAY INVISIBLE (4352 4650);
FORCEADD SCONN288_H44441003..4
(3400 1550);
FORCEPROP 1 LAST LOCATION J6M1
J 0
(2950 2650);
DISPLAY 0.617021 (2950 2650);
PAINT AQUA (2950 2650);
FORCEPROP 1 LAST PART_NUMBER H44441-003
J 0
(2950 500);
DISPLAY 0.617021 (2950 500);
PAINT BLUE (2950 500);
FORCEPROP 1 LAST MATERIAL SCONN
J 0
(2950 2600);
DISPLAY 0.617021 (2950 2600);
PAINT SKYBLUE (2950 2600);
FORCEPROP 2 LASTPIN (2900 2100) $PN 77
J 2
(2890 2110);
DISPLAY 0.617021 (2890 2110);
PAINT ORANGE (2890 2110);
FORCEPROP 2 LASTPIN (2900 2050) $PN 221
J 2
(2890 2060);
DISPLAY 0.617021 (2890 2060);
PAINT ORANGE (2890 2060);
FORCEPROP 2 LASTPIN (2900 2400) $PN 142
J 2
(2890 2410);
DISPLAY 0.617021 (2890 2410);
PAINT ORANGE (2890 2410);
FORCEPROP 2 LASTPIN (2900 2350) $PN 143
J 2
(2890 2360);
DISPLAY 0.617021 (2890 2360);
PAINT ORANGE (2890 2360);
FORCEPROP 2 LASTPIN (2900 2300) $PN 288
J 2
(2890 2310);
DISPLAY 0.617021 (2890 2310);
PAINT ORANGE (2890 2310);
FORCEPROP 2 LASTPIN (2900 2250) $PN 286
J 2
(2890 2260);
DISPLAY 0.617021 (2890 2260);
PAINT ORANGE (2890 2260);
FORCEPROP 2 LASTPIN (2900 2200) $PN 287
J 2
(2890 2210);
DISPLAY 0.617021 (2890 2210);
PAINT ORANGE (2890 2210);
FORCEPROP 2 LASTPIN (2900 1950) $PN 59
J 2
(2890 1960);
DISPLAY 0.617021 (2890 1960);
PAINT ORANGE (2890 1960);
FORCEPROP 2 LASTPIN (2900 1900) $PN 61
J 2
(2890 1910);
DISPLAY 0.617021 (2890 1910);
PAINT ORANGE (2890 1910);
FORCEPROP 2 LASTPIN (2900 1850) $PN 64
J 2
(2890 1860);
DISPLAY 0.617021 (2890 1860);
PAINT ORANGE (2890 1860);
FORCEPROP 2 LASTPIN (2900 1800) $PN 67
J 2
(2890 1810);
DISPLAY 0.617021 (2890 1810);
PAINT ORANGE (2890 1810);
FORCEPROP 2 LASTPIN (2900 1750) $PN 70
J 2
(2890 1760);
DISPLAY 0.617021 (2890 1760);
PAINT ORANGE (2890 1760);
FORCEPROP 2 LASTPIN (2900 1700) $PN 73
J 2
(2890 1710);
DISPLAY 0.617021 (2890 1710);
PAINT ORANGE (2890 1710);
FORCEPROP 2 LASTPIN (2900 1650) $PN 76
J 2
(2890 1660);
DISPLAY 0.617021 (2890 1660);
PAINT ORANGE (2890 1660);
FORCEPROP 2 LASTPIN (2900 1600) $PN 80
J 2
(2890 1610);
DISPLAY 0.617021 (2890 1610);
PAINT ORANGE (2890 1610);
FORCEPROP 2 LASTPIN (2900 1550) $PN 83
J 2
(2890 1560);
DISPLAY 0.617021 (2890 1560);
PAINT ORANGE (2890 1560);
FORCEPROP 2 LASTPIN (2900 1500) $PN 85
J 2
(2890 1510);
DISPLAY 0.617021 (2890 1510);
PAINT ORANGE (2890 1510);
FORCEPROP 2 LASTPIN (2900 1450) $PN 88
J 2
(2890 1460);
DISPLAY 0.617021 (2890 1460);
PAINT ORANGE (2890 1460);
FORCEPROP 2 LASTPIN (2900 1400) $PN 90
J 2
(2890 1410);
DISPLAY 0.617021 (2890 1410);
PAINT ORANGE (2890 1410);
FORCEPROP 2 LASTPIN (2900 1350) $PN 92
J 2
(2890 1360);
DISPLAY 0.617021 (2890 1360);
PAINT ORANGE (2890 1360);
FORCEPROP 2 LASTPIN (2900 1300) $PN 204
J 2
(2890 1310);
DISPLAY 0.617021 (2890 1310);
PAINT ORANGE (2890 1310);
FORCEPROP 2 LASTPIN (2900 1250) $PN 206
J 2
(2890 1260);
DISPLAY 0.617021 (2890 1260);
PAINT ORANGE (2890 1260);
FORCEPROP 2 LASTPIN (2900 1200) $PN 209
J 2
(2890 1210);
DISPLAY 0.617021 (2890 1210);
PAINT ORANGE (2890 1210);
FORCEPROP 2 LASTPIN (2900 1150) $PN 212
J 2
(2890 1160);
DISPLAY 0.617021 (2890 1160);
PAINT ORANGE (2890 1160);
FORCEPROP 2 LASTPIN (2900 1100) $PN 215
J 2
(2890 1110);
DISPLAY 0.617021 (2890 1110);
PAINT ORANGE (2890 1110);
FORCEPROP 2 LASTPIN (2900 1050) $PN 217
J 2
(2890 1060);
DISPLAY 0.617021 (2890 1060);
PAINT ORANGE (2890 1060);
FORCEPROP 2 LASTPIN (2900 1000) $PN 220
J 2
(2890 1010);
DISPLAY 0.617021 (2890 1010);
PAINT ORANGE (2890 1010);
FORCEPROP 2 LASTPIN (2900 950) $PN 223
J 2
(2890 960);
DISPLAY 0.617021 (2890 960);
PAINT ORANGE (2890 960);
FORCEPROP 2 LASTPIN (2900 900) $PN 226
J 2
(2890 910);
DISPLAY 0.617021 (2890 910);
PAINT ORANGE (2890 910);
FORCEPROP 2 LASTPIN (2900 850) $PN 229
J 2
(2890 860);
DISPLAY 0.617021 (2890 860);
PAINT ORANGE (2890 860);
FORCEPROP 2 LASTPIN (2900 800) $PN 231
J 2
(2890 810);
DISPLAY 0.617021 (2890 810);
PAINT ORANGE (2890 810);
FORCEPROP 2 LASTPIN (2900 750) $PN 233
J 2
(2890 760);
DISPLAY 0.617021 (2890 760);
PAINT ORANGE (2890 760);
FORCEPROP 2 LASTPIN (2900 700) $PN 236
J 2
(2890 710);
DISPLAY 0.617021 (2890 710);
PAINT ORANGE (2890 710);
FORCEPROP 2 LASTPIN (3900 2400) $PN 1
J 0
(3910 2410);
DISPLAY 0.617021 (3910 2410);
PAINT ORANGE (3910 2410);
FORCEPROP 2 LASTPIN (3900 2350) $PN 145
J 0
(3910 2360);
DISPLAY 0.617021 (3910 2360);
PAINT ORANGE (3910 2360);
FORCEPROP 1 LAST PACK_TYPE PIP
J 0
(2950 2700);
PAINT SKYBLUE (2950 2700);
DISPLAY INVISIBLE (2950 2700);
FORCEPROP 2 LAST BOM_COST MEM
J 0
(3400 1550);
PAINT ORANGE (3400 1550);
DISPLAY INVISIBLE (3400 1550);
FORCEPROP 2 LAST CDS_LIB mstr_sconn
J 0
(3400 1550);
PAINT ORANGE (3400 1550);
DISPLAY INVISIBLE (3400 1550);
FORCEPROP 2 LAST SEC_TYPE PIP
J 0
(2950 2700);
DISPLAY 1.021277 (2950 2700);
PAINT ORANGE (2950 2700);
DISPLAY INVISIBLE (2950 2700);
FORCEPROP 2 LAST SEC 4
J 0
(2950 2700);
DISPLAY 0.680851 (2950 2700);
PAINT MONO (2950 2700);
DISPLAY INVISIBLE (2950 2700);
FORCEPROP 2 LAST CDS_LOCATION J6M1
J 0
(2950 2650);
DISPLAY 0.617021 (2950 2650);
PAINT AQUA (2950 2650);
DISPLAY INVISIBLE (2950 2650);
FORCEPROP 1 LAST PATH I50
J 0
(3400 2600);
PAINT GREEN (3400 2600);
DISPLAY INVISIBLE (3400 2600);
FORCEPROP 2 LAST ROOM DDR4_CH_D
J 0
(3400 1550);
PAINT ORANGE (3400 1550);
DISPLAY INVISIBLE (3400 1550);
FORCEADD TAP..6
R 2
(1700 4700);
FORCEPROP 3 LASTPIN (1650 4700) SIG_NAME M_D_DQ<62>
J 0
(1660 4710);
DISPLAY 0.659574 (1660 4710);
PAINT MONO (1660 4710);
DISPLAY INVISIBLE (1660 4710);
FORCEPROP 1 LASTPIN (1650 4700) BN 62
J 2
(1700 4710);
DISPLAY 0.617021 (1700 4710);
PAINT PINK (1700 4710);
FORCEPROP 2 LAST CDS_LIB mstr_standard
J 2
(1700 4700);
DISPLAY 0.787234 (1700 4700);
PAINT MONO (1700 4700);
DISPLAY INVISIBLE (1700 4700);
FORCEPROP 1 LAST BODY_TYPE PLUMBING
J 2
(1700 4650);
DISPLAY 1.234043 (1700 4650);
PAINT GREEN (1700 4650);
DISPLAY INVISIBLE (1700 4650);
FORCEPROP 1 LAST HDL_TAP TRUE
J 2
(1375 4575);
DISPLAY 1.234043 (1375 4575);
PAINT GREEN (1375 4575);
DISPLAY INVISIBLE (1375 4575);
FORCEPROP 1 LAST PATH I51
J 2
(1702 4700);
DISPLAY 0.872340 (1702 4700);
PAINT GREEN (1702 4700);
DISPLAY INVISIBLE (1702 4700);
FORCEADD TAP..6
R 2
(1700 4600);
FORCEPROP 3 LASTPIN (1650 4600) SIG_NAME M_D_DQ<60>
J 0
(1660 4610);
DISPLAY 0.659574 (1660 4610);
PAINT MONO (1660 4610);
DISPLAY INVISIBLE (1660 4610);
FORCEPROP 1 LASTPIN (1650 4600) BN 60
J 2
(1700 4610);
DISPLAY 0.617021 (1700 4610);
PAINT PINK (1700 4610);
FORCEPROP 2 LAST CDS_LIB mstr_standard
J 2
(1700 4600);
DISPLAY 0.787234 (1700 4600);
PAINT MONO (1700 4600);
DISPLAY INVISIBLE (1700 4600);
FORCEPROP 1 LAST BODY_TYPE PLUMBING
J 2
(1700 4550);
DISPLAY 1.234043 (1700 4550);
PAINT GREEN (1700 4550);
DISPLAY INVISIBLE (1700 4550);
FORCEPROP 1 LAST HDL_TAP TRUE
J 2
(1375 4475);
DISPLAY 1.234043 (1375 4475);
PAINT GREEN (1375 4475);
DISPLAY INVISIBLE (1375 4475);
FORCEPROP 1 LAST PATH I52
J 2
(1702 4600);
DISPLAY 0.872340 (1702 4600);
PAINT GREEN (1702 4600);
DISPLAY INVISIBLE (1702 4600);
FORCEADD TAP..6
R 2
(1700 4650);
FORCEPROP 3 LASTPIN (1650 4650) SIG_NAME M_D_DQ<61>
J 0
(1660 4660);
DISPLAY 0.659574 (1660 4660);
PAINT MONO (1660 4660);
DISPLAY INVISIBLE (1660 4660);
FORCEPROP 1 LASTPIN (1650 4650) BN 61
J 2
(1700 4660);
DISPLAY 0.617021 (1700 4660);
PAINT PINK (1700 4660);
FORCEPROP 2 LAST CDS_LIB mstr_standard
J 2
(1700 4650);
DISPLAY 0.787234 (1700 4650);
PAINT MONO (1700 4650);
DISPLAY INVISIBLE (1700 4650);
FORCEPROP 1 LAST BODY_TYPE PLUMBING
J 2
(1700 4600);
DISPLAY 1.234043 (1700 4600);
PAINT GREEN (1700 4600);
DISPLAY INVISIBLE (1700 4600);
FORCEPROP 1 LAST HDL_TAP TRUE
J 2
(1375 4525);
DISPLAY 1.234043 (1375 4525);
PAINT GREEN (1375 4525);
DISPLAY INVISIBLE (1375 4525);
FORCEPROP 1 LAST PATH I53
J 2
(1702 4650);
DISPLAY 0.872340 (1702 4650);
PAINT GREEN (1702 4650);
DISPLAY INVISIBLE (1702 4650);
FORCEADD TAP..6
R 2
(1700 4750);
FORCEPROP 3 LASTPIN (1650 4750) SIG_NAME M_D_DQ<63>
J 0
(1660 4760);
DISPLAY 0.659574 (1660 4760);
PAINT MONO (1660 4760);
DISPLAY INVISIBLE (1660 4760);
FORCEPROP 1 LASTPIN (1650 4750) BN 63
J 2
(1700 4760);
DISPLAY 0.617021 (1700 4760);
PAINT PINK (1700 4760);
FORCEPROP 2 LAST CDS_LIB mstr_standard
J 2
(1700 4750);
DISPLAY 0.787234 (1700 4750);
PAINT MONO (1700 4750);
DISPLAY INVISIBLE (1700 4750);
FORCEPROP 1 LAST BODY_TYPE PLUMBING
J 2
(1700 4700);
DISPLAY 1.234043 (1700 4700);
PAINT GREEN (1700 4700);
DISPLAY INVISIBLE (1700 4700);
FORCEPROP 1 LAST HDL_TAP TRUE
J 2
(1375 4625);
DISPLAY 1.234043 (1375 4625);
PAINT GREEN (1375 4625);
DISPLAY INVISIBLE (1375 4625);
FORCEPROP 1 LAST PATH I54
J 2
(1702 4750);
DISPLAY 0.872340 (1702 4750);
PAINT GREEN (1702 4750);
DISPLAY INVISIBLE (1702 4750);
FORCEADD TAP..6
R 2
(1700 4350);
FORCEPROP 3 LASTPIN (1650 4350) SIG_NAME M_D_DQ<55>
J 0
(1660 4360);
DISPLAY 0.659574 (1660 4360);
PAINT MONO (1660 4360);
DISPLAY INVISIBLE (1660 4360);
FORCEPROP 1 LASTPIN (1650 4350) BN 55
J 2
(1700 4360);
DISPLAY 0.617021 (1700 4360);
PAINT PINK (1700 4360);
FORCEPROP 2 LAST CDS_LIB mstr_standard
J 2
(1700 4350);
DISPLAY 0.787234 (1700 4350);
PAINT MONO (1700 4350);
DISPLAY INVISIBLE (1700 4350);
FORCEPROP 1 LAST BODY_TYPE PLUMBING
J 2
(1700 4300);
DISPLAY 1.234043 (1700 4300);
PAINT GREEN (1700 4300);
DISPLAY INVISIBLE (1700 4300);
FORCEPROP 1 LAST HDL_TAP TRUE
J 2
(1375 4225);
DISPLAY 1.234043 (1375 4225);
PAINT GREEN (1375 4225);
DISPLAY INVISIBLE (1375 4225);
FORCEPROP 1 LAST PATH I55
J 2
(1702 4350);
DISPLAY 0.872340 (1702 4350);
PAINT GREEN (1702 4350);
DISPLAY INVISIBLE (1702 4350);
FORCEADD TAP..6
R 2
(1700 4400);
FORCEPROP 3 LASTPIN (1650 4400) SIG_NAME M_D_DQ<56>
J 0
(1660 4410);
DISPLAY 0.659574 (1660 4410);
PAINT MONO (1660 4410);
DISPLAY INVISIBLE (1660 4410);
FORCEPROP 1 LASTPIN (1650 4400) BN 56
J 2
(1700 4410);
DISPLAY 0.617021 (1700 4410);
PAINT PINK (1700 4410);
FORCEPROP 2 LAST CDS_LIB mstr_standard
J 2
(1700 4400);
DISPLAY 0.787234 (1700 4400);
PAINT MONO (1700 4400);
DISPLAY INVISIBLE (1700 4400);
FORCEPROP 1 LAST BODY_TYPE PLUMBING
J 2
(1700 4350);
DISPLAY 1.234043 (1700 4350);
PAINT GREEN (1700 4350);
DISPLAY INVISIBLE (1700 4350);
FORCEPROP 1 LAST HDL_TAP TRUE
J 2
(1375 4275);
DISPLAY 1.234043 (1375 4275);
PAINT GREEN (1375 4275);
DISPLAY INVISIBLE (1375 4275);
FORCEPROP 1 LAST PATH I56
J 2
(1702 4400);
DISPLAY 0.872340 (1702 4400);
PAINT GREEN (1702 4400);
DISPLAY INVISIBLE (1702 4400);
FORCEADD TAP..6
R 2
(1700 4450);
FORCEPROP 3 LASTPIN (1650 4450) SIG_NAME M_D_DQ<57>
J 0
(1660 4460);
DISPLAY 0.659574 (1660 4460);
PAINT MONO (1660 4460);
DISPLAY INVISIBLE (1660 4460);
FORCEPROP 1 LASTPIN (1650 4450) BN 57
J 2
(1700 4460);
DISPLAY 0.617021 (1700 4460);
PAINT PINK (1700 4460);
FORCEPROP 2 LAST CDS_LIB mstr_standard
J 2
(1700 4450);
DISPLAY 0.787234 (1700 4450);
PAINT MONO (1700 4450);
DISPLAY INVISIBLE (1700 4450);
FORCEPROP 1 LAST BODY_TYPE PLUMBING
J 2
(1700 4400);
DISPLAY 1.234043 (1700 4400);
PAINT GREEN (1700 4400);
DISPLAY INVISIBLE (1700 4400);
FORCEPROP 1 LAST HDL_TAP TRUE
J 2
(1375 4325);
DISPLAY 1.234043 (1375 4325);
PAINT GREEN (1375 4325);
DISPLAY INVISIBLE (1375 4325);
FORCEPROP 1 LAST PATH I57
J 2
(1702 4450);
DISPLAY 0.872340 (1702 4450);
PAINT GREEN (1702 4450);
DISPLAY INVISIBLE (1702 4450);
FORCEADD TAP..6
R 2
(1700 4550);
FORCEPROP 3 LASTPIN (1650 4550) SIG_NAME M_D_DQ<59>
J 0
(1660 4560);
DISPLAY 0.659574 (1660 4560);
PAINT MONO (1660 4560);
DISPLAY INVISIBLE (1660 4560);
FORCEPROP 1 LASTPIN (1650 4550) BN 59
J 2
(1700 4560);
DISPLAY 0.617021 (1700 4560);
PAINT PINK (1700 4560);
FORCEPROP 2 LAST CDS_LIB mstr_standard
J 2
(1700 4550);
DISPLAY 0.787234 (1700 4550);
PAINT MONO (1700 4550);
DISPLAY INVISIBLE (1700 4550);
FORCEPROP 1 LAST BODY_TYPE PLUMBING
J 2
(1700 4500);
DISPLAY 1.234043 (1700 4500);
PAINT GREEN (1700 4500);
DISPLAY INVISIBLE (1700 4500);
FORCEPROP 1 LAST HDL_TAP TRUE
J 2
(1375 4425);
DISPLAY 1.234043 (1375 4425);
PAINT GREEN (1375 4425);
DISPLAY INVISIBLE (1375 4425);
FORCEPROP 1 LAST PATH I58
J 2
(1702 4550);
DISPLAY 0.872340 (1702 4550);
PAINT GREEN (1702 4550);
DISPLAY INVISIBLE (1702 4550);
FORCEADD TAP..6
R 2
(1700 4500);
FORCEPROP 3 LASTPIN (1650 4500) SIG_NAME M_D_DQ<58>
J 0
(1660 4510);
DISPLAY 0.659574 (1660 4510);
PAINT MONO (1660 4510);
DISPLAY INVISIBLE (1660 4510);
FORCEPROP 1 LASTPIN (1650 4500) BN 58
J 2
(1700 4510);
DISPLAY 0.617021 (1700 4510);
PAINT PINK (1700 4510);
FORCEPROP 2 LAST CDS_LIB mstr_standard
J 2
(1700 4500);
DISPLAY 0.787234 (1700 4500);
PAINT MONO (1700 4500);
DISPLAY INVISIBLE (1700 4500);
FORCEPROP 1 LAST BODY_TYPE PLUMBING
J 2
(1700 4450);
DISPLAY 1.234043 (1700 4450);
PAINT GREEN (1700 4450);
DISPLAY INVISIBLE (1700 4450);
FORCEPROP 1 LAST HDL_TAP TRUE
J 2
(1375 4375);
DISPLAY 1.234043 (1375 4375);
PAINT GREEN (1375 4375);
DISPLAY INVISIBLE (1375 4375);
FORCEPROP 1 LAST PATH I59
J 2
(1702 4500);
DISPLAY 0.872340 (1702 4500);
PAINT GREEN (1702 4500);
DISPLAY INVISIBLE (1702 4500);
FORCEADD TAP..6
R 2
(4100 4800);
FORCEPROP 3 LASTPIN (4050 4800) SIG_NAME M_D_DQS_DP<17>
J 0
(4060 4810);
DISPLAY 0.659574 (4060 4810);
PAINT MONO (4060 4810);
DISPLAY INVISIBLE (4060 4810);
FORCEPROP 1 LASTPIN (4050 4800) BN 17
J 2
(4100 4810);
DISPLAY 0.617021 (4100 4810);
PAINT PINK (4100 4810);
FORCEPROP 2 LAST CDS_LIB mstr_standard
J 2
(4100 4800);
DISPLAY 0.787234 (4100 4800);
PAINT MONO (4100 4800);
DISPLAY INVISIBLE (4100 4800);
FORCEPROP 1 LAST BODY_TYPE PLUMBING
J 2
(4100 4750);
DISPLAY 1.234043 (4100 4750);
PAINT GREEN (4100 4750);
DISPLAY INVISIBLE (4100 4750);
FORCEPROP 1 LAST HDL_TAP TRUE
J 2
(3775 4675);
DISPLAY 1.234043 (3775 4675);
PAINT GREEN (3775 4675);
DISPLAY INVISIBLE (3775 4675);
FORCEPROP 1 LAST PATH I6
J 2
(4102 4800);
DISPLAY 0.872340 (4102 4800);
PAINT GREEN (4102 4800);
DISPLAY INVISIBLE (4102 4800);
FORCEADD TAP..6
R 2
(1700 4200);
FORCEPROP 3 LASTPIN (1650 4200) SIG_NAME M_D_DQ<52>
J 0
(1660 4210);
DISPLAY 0.659574 (1660 4210);
PAINT MONO (1660 4210);
DISPLAY INVISIBLE (1660 4210);
FORCEPROP 1 LASTPIN (1650 4200) BN 52
J 2
(1700 4210);
DISPLAY 0.617021 (1700 4210);
PAINT PINK (1700 4210);
FORCEPROP 2 LAST CDS_LIB mstr_standard
J 2
(1700 4200);
DISPLAY 0.787234 (1700 4200);
PAINT MONO (1700 4200);
DISPLAY INVISIBLE (1700 4200);
FORCEPROP 1 LAST BODY_TYPE PLUMBING
J 2
(1700 4150);
DISPLAY 1.234043 (1700 4150);
PAINT GREEN (1700 4150);
DISPLAY INVISIBLE (1700 4150);
FORCEPROP 1 LAST HDL_TAP TRUE
J 2
(1375 4075);
DISPLAY 1.234043 (1375 4075);
PAINT GREEN (1375 4075);
DISPLAY INVISIBLE (1375 4075);
FORCEPROP 1 LAST PATH I60
J 2
(1702 4200);
DISPLAY 0.872340 (1702 4200);
PAINT GREEN (1702 4200);
DISPLAY INVISIBLE (1702 4200);
FORCEADD TAP..6
R 2
(1700 4150);
FORCEPROP 3 LASTPIN (1650 4150) SIG_NAME M_D_DQ<51>
J 0
(1660 4160);
DISPLAY 0.659574 (1660 4160);
PAINT MONO (1660 4160);
DISPLAY INVISIBLE (1660 4160);
FORCEPROP 1 LASTPIN (1650 4150) BN 51
J 2
(1700 4160);
DISPLAY 0.617021 (1700 4160);
PAINT PINK (1700 4160);
FORCEPROP 2 LAST CDS_LIB mstr_standard
J 2
(1700 4150);
DISPLAY 0.787234 (1700 4150);
PAINT MONO (1700 4150);
DISPLAY INVISIBLE (1700 4150);
FORCEPROP 1 LAST BODY_TYPE PLUMBING
J 2
(1700 4100);
DISPLAY 1.234043 (1700 4100);
PAINT GREEN (1700 4100);
DISPLAY INVISIBLE (1700 4100);
FORCEPROP 1 LAST HDL_TAP TRUE
J 2
(1375 4025);
DISPLAY 1.234043 (1375 4025);
PAINT GREEN (1375 4025);
DISPLAY INVISIBLE (1375 4025);
FORCEPROP 1 LAST PATH I61
J 2
(1702 4150);
DISPLAY 0.872340 (1702 4150);
PAINT GREEN (1702 4150);
DISPLAY INVISIBLE (1702 4150);
FORCEADD TAP..6
R 2
(1700 4100);
FORCEPROP 3 LASTPIN (1650 4100) SIG_NAME M_D_DQ<50>
J 0
(1660 4110);
DISPLAY 0.659574 (1660 4110);
PAINT MONO (1660 4110);
DISPLAY INVISIBLE (1660 4110);
FORCEPROP 1 LASTPIN (1650 4100) BN 50
J 2
(1700 4110);
DISPLAY 0.617021 (1700 4110);
PAINT PINK (1700 4110);
FORCEPROP 2 LAST CDS_LIB mstr_standard
J 2
(1700 4100);
DISPLAY 0.787234 (1700 4100);
PAINT MONO (1700 4100);
DISPLAY INVISIBLE (1700 4100);
FORCEPROP 1 LAST BODY_TYPE PLUMBING
J 2
(1700 4050);
DISPLAY 1.234043 (1700 4050);
PAINT GREEN (1700 4050);
DISPLAY INVISIBLE (1700 4050);
FORCEPROP 1 LAST HDL_TAP TRUE
J 2
(1375 3975);
DISPLAY 1.234043 (1375 3975);
PAINT GREEN (1375 3975);
DISPLAY INVISIBLE (1375 3975);
FORCEPROP 1 LAST PATH I62
J 2
(1702 4100);
DISPLAY 0.872340 (1702 4100);
PAINT GREEN (1702 4100);
DISPLAY INVISIBLE (1702 4100);
FORCEADD TAP..6
R 2
(1700 4250);
FORCEPROP 3 LASTPIN (1650 4250) SIG_NAME M_D_DQ<53>
J 0
(1660 4260);
DISPLAY 0.659574 (1660 4260);
PAINT MONO (1660 4260);
DISPLAY INVISIBLE (1660 4260);
FORCEPROP 1 LASTPIN (1650 4250) BN 53
J 2
(1700 4260);
DISPLAY 0.617021 (1700 4260);
PAINT PINK (1700 4260);
FORCEPROP 2 LAST CDS_LIB mstr_standard
J 2
(1700 4250);
DISPLAY 0.787234 (1700 4250);
PAINT MONO (1700 4250);
DISPLAY INVISIBLE (1700 4250);
FORCEPROP 1 LAST BODY_TYPE PLUMBING
J 2
(1700 4200);
DISPLAY 1.234043 (1700 4200);
PAINT GREEN (1700 4200);
DISPLAY INVISIBLE (1700 4200);
FORCEPROP 1 LAST HDL_TAP TRUE
J 2
(1375 4125);
DISPLAY 1.234043 (1375 4125);
PAINT GREEN (1375 4125);
DISPLAY INVISIBLE (1375 4125);
FORCEPROP 1 LAST PATH I63
J 2
(1702 4250);
DISPLAY 0.872340 (1702 4250);
PAINT GREEN (1702 4250);
DISPLAY INVISIBLE (1702 4250);
FORCEADD TAP..6
R 2
(1700 4300);
FORCEPROP 3 LASTPIN (1650 4300) SIG_NAME M_D_DQ<54>
J 0
(1660 4310);
DISPLAY 0.659574 (1660 4310);
PAINT MONO (1660 4310);
DISPLAY INVISIBLE (1660 4310);
FORCEPROP 1 LASTPIN (1650 4300) BN 54
J 2
(1700 4310);
DISPLAY 0.617021 (1700 4310);
PAINT PINK (1700 4310);
FORCEPROP 2 LAST CDS_LIB mstr_standard
J 2
(1700 4300);
DISPLAY 0.787234 (1700 4300);
PAINT MONO (1700 4300);
DISPLAY INVISIBLE (1700 4300);
FORCEPROP 1 LAST BODY_TYPE PLUMBING
J 2
(1700 4250);
DISPLAY 1.234043 (1700 4250);
PAINT GREEN (1700 4250);
DISPLAY INVISIBLE (1700 4250);
FORCEPROP 1 LAST HDL_TAP TRUE
J 2
(1375 4175);
DISPLAY 1.234043 (1375 4175);
PAINT GREEN (1375 4175);
DISPLAY INVISIBLE (1375 4175);
FORCEPROP 1 LAST PATH I64
J 2
(1702 4300);
DISPLAY 0.872340 (1702 4300);
PAINT GREEN (1702 4300);
DISPLAY INVISIBLE (1702 4300);
FORCEADD TAP..6
(200 4700);
FORCEPROP 3 LASTPIN (250 4700) SIG_NAME M_D_MA<16>
J 0
(260 4710);
DISPLAY 0.659574 (260 4710);
PAINT MONO (260 4710);
DISPLAY INVISIBLE (260 4710);
FORCEPROP 1 LASTPIN (250 4700) BN 16
J 0
(200 4710);
DISPLAY 0.617021 (200 4710);
PAINT PINK (200 4710);
FORCEPROP 2 LAST CDS_LIB mstr_standard
J 2
(200 4700);
DISPLAY 0.787234 (200 4700);
PAINT MONO (200 4700);
DISPLAY INVISIBLE (200 4700);
FORCEPROP 1 LAST BODY_TYPE PLUMBING
J 0
(200 4650);
DISPLAY 1.234043 (200 4650);
PAINT GREEN (200 4650);
DISPLAY INVISIBLE (200 4650);
FORCEPROP 1 LAST HDL_TAP TRUE
J 0
(525 4575);
DISPLAY 1.234043 (525 4575);
PAINT GREEN (525 4575);
DISPLAY INVISIBLE (525 4575);
FORCEPROP 1 LAST PATH I65
J 0
(198 4700);
DISPLAY 0.872340 (198 4700);
PAINT GREEN (198 4700);
DISPLAY INVISIBLE (198 4700);
FORCEADD TAP..6
(200 4750);
FORCEPROP 3 LASTPIN (250 4750) SIG_NAME M_D_MA<17>
J 0
(260 4760);
DISPLAY 0.659574 (260 4760);
PAINT MONO (260 4760);
DISPLAY INVISIBLE (260 4760);
FORCEPROP 1 LASTPIN (250 4750) BN 17
J 0
(200 4760);
DISPLAY 0.617021 (200 4760);
PAINT PINK (200 4760);
FORCEPROP 2 LAST CDS_LIB mstr_standard
J 0
(200 4750);
DISPLAY 0.787234 (200 4750);
PAINT MONO (200 4750);
DISPLAY INVISIBLE (200 4750);
FORCEPROP 1 LAST BODY_TYPE PLUMBING
J 0
(200 4700);
DISPLAY 1.234043 (200 4700);
PAINT GREEN (200 4700);
DISPLAY INVISIBLE (200 4700);
FORCEPROP 1 LAST HDL_TAP TRUE
J 0
(525 4625);
DISPLAY 1.234043 (525 4625);
PAINT GREEN (525 4625);
DISPLAY INVISIBLE (525 4625);
FORCEPROP 1 LAST PATH I66
J 0
(198 4750);
DISPLAY 0.872340 (198 4750);
PAINT GREEN (198 4750);
DISPLAY INVISIBLE (198 4750);
FORCEADD TAP..6
(200 4650);
FORCEPROP 3 LASTPIN (250 4650) SIG_NAME M_D_MA<15>
J 0
(260 4660);
DISPLAY 0.659574 (260 4660);
PAINT MONO (260 4660);
DISPLAY INVISIBLE (260 4660);
FORCEPROP 1 LASTPIN (250 4650) BN 15
J 0
(200 4660);
DISPLAY 0.617021 (200 4660);
PAINT PINK (200 4660);
FORCEPROP 2 LAST CDS_LIB mstr_standard
J 2
(200 4650);
DISPLAY 0.787234 (200 4650);
PAINT MONO (200 4650);
DISPLAY INVISIBLE (200 4650);
FORCEPROP 1 LAST BODY_TYPE PLUMBING
J 0
(200 4600);
DISPLAY 1.234043 (200 4600);
PAINT GREEN (200 4600);
DISPLAY INVISIBLE (200 4600);
FORCEPROP 1 LAST HDL_TAP TRUE
J 0
(525 4525);
DISPLAY 1.234043 (525 4525);
PAINT GREEN (525 4525);
DISPLAY INVISIBLE (525 4525);
FORCEPROP 1 LAST PATH I67
J 0
(198 4650);
DISPLAY 0.872340 (198 4650);
PAINT GREEN (198 4650);
DISPLAY INVISIBLE (198 4650);
FORCEADD TAP..6
(200 4600);
FORCEPROP 3 LASTPIN (250 4600) SIG_NAME M_D_MA<14>
J 0
(260 4610);
DISPLAY 0.659574 (260 4610);
PAINT MONO (260 4610);
DISPLAY INVISIBLE (260 4610);
FORCEPROP 1 LASTPIN (250 4600) BN 14
J 0
(200 4610);
DISPLAY 0.617021 (200 4610);
PAINT PINK (200 4610);
FORCEPROP 2 LAST CDS_LIB mstr_standard
J 2
(200 4600);
DISPLAY 0.787234 (200 4600);
PAINT MONO (200 4600);
DISPLAY INVISIBLE (200 4600);
FORCEPROP 1 LAST BODY_TYPE PLUMBING
J 0
(200 4550);
DISPLAY 1.234043 (200 4550);
PAINT GREEN (200 4550);
DISPLAY INVISIBLE (200 4550);
FORCEPROP 1 LAST HDL_TAP TRUE
J 0
(525 4475);
DISPLAY 1.234043 (525 4475);
PAINT GREEN (525 4475);
DISPLAY INVISIBLE (525 4475);
FORCEPROP 1 LAST PATH I68
J 0
(198 4600);
DISPLAY 0.872340 (198 4600);
PAINT GREEN (198 4600);
DISPLAY INVISIBLE (198 4600);
FORCEADD TAP..6
(200 4550);
FORCEPROP 3 LASTPIN (250 4550) SIG_NAME M_D_MA<13>
J 0
(260 4560);
DISPLAY 0.659574 (260 4560);
PAINT MONO (260 4560);
DISPLAY INVISIBLE (260 4560);
FORCEPROP 1 LASTPIN (250 4550) BN 13
J 0
(200 4560);
DISPLAY 0.617021 (200 4560);
PAINT PINK (200 4560);
FORCEPROP 2 LAST CDS_LIB mstr_standard
J 2
(200 4550);
DISPLAY 0.787234 (200 4550);
PAINT MONO (200 4550);
DISPLAY INVISIBLE (200 4550);
FORCEPROP 1 LAST BODY_TYPE PLUMBING
J 0
(200 4500);
DISPLAY 1.234043 (200 4500);
PAINT GREEN (200 4500);
DISPLAY INVISIBLE (200 4500);
FORCEPROP 1 LAST HDL_TAP TRUE
J 0
(525 4425);
DISPLAY 1.234043 (525 4425);
PAINT GREEN (525 4425);
DISPLAY INVISIBLE (525 4425);
FORCEPROP 1 LAST PATH I69
J 0
(198 4550);
DISPLAY 0.872340 (198 4550);
PAINT GREEN (198 4550);
DISPLAY INVISIBLE (198 4550);
FORCEADD TAP..6
R 2
(4100 4600);
FORCEPROP 3 LASTPIN (4050 4600) SIG_NAME M_D_DQS_DP<15>
J 0
(4060 4610);
DISPLAY 0.659574 (4060 4610);
PAINT MONO (4060 4610);
DISPLAY INVISIBLE (4060 4610);
FORCEPROP 1 LASTPIN (4050 4600) BN 15
J 2
(4100 4610);
DISPLAY 0.617021 (4100 4610);
PAINT PINK (4100 4610);
FORCEPROP 2 LAST CDS_LIB mstr_standard
J 0
(4100 4600);
DISPLAY 0.787234 (4100 4600);
PAINT MONO (4100 4600);
DISPLAY INVISIBLE (4100 4600);
FORCEPROP 1 LAST BODY_TYPE PLUMBING
J 2
(4100 4550);
DISPLAY 1.234043 (4100 4550);
PAINT GREEN (4100 4550);
DISPLAY INVISIBLE (4100 4550);
FORCEPROP 1 LAST HDL_TAP TRUE
J 2
(3775 4475);
DISPLAY 1.234043 (3775 4475);
PAINT GREEN (3775 4475);
DISPLAY INVISIBLE (3775 4475);
FORCEPROP 1 LAST PATH I7
J 2
(4102 4600);
DISPLAY 0.872340 (4102 4600);
PAINT GREEN (4102 4600);
DISPLAY INVISIBLE (4102 4600);
FORCEADD TAP..6
(200 4500);
FORCEPROP 3 LASTPIN (250 4500) SIG_NAME M_D_MA<12>
J 0
(260 4510);
DISPLAY 0.659574 (260 4510);
PAINT MONO (260 4510);
DISPLAY INVISIBLE (260 4510);
FORCEPROP 1 LASTPIN (250 4500) BN 12
J 0
(200 4510);
DISPLAY 0.617021 (200 4510);
PAINT PINK (200 4510);
FORCEPROP 2 LAST CDS_LIB mstr_standard
J 2
(200 4500);
DISPLAY 0.787234 (200 4500);
PAINT MONO (200 4500);
DISPLAY INVISIBLE (200 4500);
FORCEPROP 1 LAST BODY_TYPE PLUMBING
J 0
(200 4450);
DISPLAY 1.234043 (200 4450);
PAINT GREEN (200 4450);
DISPLAY INVISIBLE (200 4450);
FORCEPROP 1 LAST HDL_TAP TRUE
J 0
(525 4375);
DISPLAY 1.234043 (525 4375);
PAINT GREEN (525 4375);
DISPLAY INVISIBLE (525 4375);
FORCEPROP 1 LAST PATH I70
J 0
(198 4500);
DISPLAY 0.872340 (198 4500);
PAINT GREEN (198 4500);
DISPLAY INVISIBLE (198 4500);
FORCEADD TAP..6
(200 4450);
FORCEPROP 3 LASTPIN (250 4450) SIG_NAME M_D_MA<11>
J 0
(260 4460);
DISPLAY 0.659574 (260 4460);
PAINT MONO (260 4460);
DISPLAY INVISIBLE (260 4460);
FORCEPROP 1 LASTPIN (250 4450) BN 11
J 0
(200 4460);
DISPLAY 0.617021 (200 4460);
PAINT PINK (200 4460);
FORCEPROP 2 LAST CDS_LIB mstr_standard
J 2
(200 4450);
DISPLAY 0.787234 (200 4450);
PAINT MONO (200 4450);
DISPLAY INVISIBLE (200 4450);
FORCEPROP 1 LAST BODY_TYPE PLUMBING
J 0
(200 4400);
DISPLAY 1.234043 (200 4400);
PAINT GREEN (200 4400);
DISPLAY INVISIBLE (200 4400);
FORCEPROP 1 LAST HDL_TAP TRUE
J 0
(525 4325);
DISPLAY 1.234043 (525 4325);
PAINT GREEN (525 4325);
DISPLAY INVISIBLE (525 4325);
FORCEPROP 1 LAST PATH I71
J 0
(198 4450);
DISPLAY 0.872340 (198 4450);
PAINT GREEN (198 4450);
DISPLAY INVISIBLE (198 4450);
FORCEADD TAP..6
(200 4400);
FORCEPROP 3 LASTPIN (250 4400) SIG_NAME M_D_MA<10>
J 0
(260 4410);
DISPLAY 0.659574 (260 4410);
PAINT MONO (260 4410);
DISPLAY INVISIBLE (260 4410);
FORCEPROP 1 LASTPIN (250 4400) BN 10
J 0
(200 4410);
DISPLAY 0.617021 (200 4410);
PAINT PINK (200 4410);
FORCEPROP 2 LAST CDS_LIB mstr_standard
J 2
(200 4400);
DISPLAY 0.787234 (200 4400);
PAINT MONO (200 4400);
DISPLAY INVISIBLE (200 4400);
FORCEPROP 1 LAST BODY_TYPE PLUMBING
J 0
(200 4350);
DISPLAY 1.234043 (200 4350);
PAINT GREEN (200 4350);
DISPLAY INVISIBLE (200 4350);
FORCEPROP 1 LAST HDL_TAP TRUE
J 0
(525 4275);
DISPLAY 1.234043 (525 4275);
PAINT GREEN (525 4275);
DISPLAY INVISIBLE (525 4275);
FORCEPROP 1 LAST PATH I72
J 0
(198 4400);
DISPLAY 0.872340 (198 4400);
PAINT GREEN (198 4400);
DISPLAY INVISIBLE (198 4400);
FORCEADD TAP..6
(200 4350);
FORCEPROP 3 LASTPIN (250 4350) SIG_NAME M_D_MA<9>
J 0
(260 4360);
DISPLAY 0.659574 (260 4360);
PAINT MONO (260 4360);
DISPLAY INVISIBLE (260 4360);
FORCEPROP 1 LASTPIN (250 4350) BN 9
J 0
(200 4360);
DISPLAY 0.617021 (200 4360);
PAINT PINK (200 4360);
FORCEPROP 2 LAST CDS_LIB mstr_standard
J 2
(200 4350);
DISPLAY 0.787234 (200 4350);
PAINT MONO (200 4350);
DISPLAY INVISIBLE (200 4350);
FORCEPROP 1 LAST BODY_TYPE PLUMBING
J 0
(200 4300);
DISPLAY 1.234043 (200 4300);
PAINT GREEN (200 4300);
DISPLAY INVISIBLE (200 4300);
FORCEPROP 1 LAST HDL_TAP TRUE
J 0
(525 4225);
DISPLAY 1.234043 (525 4225);
PAINT GREEN (525 4225);
DISPLAY INVISIBLE (525 4225);
FORCEPROP 1 LAST PATH I73
J 0
(198 4350);
DISPLAY 0.872340 (198 4350);
PAINT GREEN (198 4350);
DISPLAY INVISIBLE (198 4350);
FORCEADD TAP..6
(200 4300);
FORCEPROP 3 LASTPIN (250 4300) SIG_NAME M_D_MA<8>
J 0
(260 4310);
DISPLAY 0.659574 (260 4310);
PAINT MONO (260 4310);
DISPLAY INVISIBLE (260 4310);
FORCEPROP 1 LASTPIN (250 4300) BN 8
J 0
(200 4310);
DISPLAY 0.617021 (200 4310);
PAINT PINK (200 4310);
FORCEPROP 2 LAST CDS_LIB mstr_standard
J 2
(200 4300);
DISPLAY 0.787234 (200 4300);
PAINT MONO (200 4300);
DISPLAY INVISIBLE (200 4300);
FORCEPROP 1 LAST BODY_TYPE PLUMBING
J 0
(200 4250);
DISPLAY 1.234043 (200 4250);
PAINT GREEN (200 4250);
DISPLAY INVISIBLE (200 4250);
FORCEPROP 1 LAST HDL_TAP TRUE
J 0
(525 4175);
DISPLAY 1.234043 (525 4175);
PAINT GREEN (525 4175);
DISPLAY INVISIBLE (525 4175);
FORCEPROP 1 LAST PATH I74
J 0
(198 4300);
DISPLAY 0.872340 (198 4300);
PAINT GREEN (198 4300);
DISPLAY INVISIBLE (198 4300);
FORCEADD TAP..6
(200 4250);
FORCEPROP 3 LASTPIN (250 4250) SIG_NAME M_D_MA<7>
J 0
(260 4260);
DISPLAY 0.659574 (260 4260);
PAINT MONO (260 4260);
DISPLAY INVISIBLE (260 4260);
FORCEPROP 1 LASTPIN (250 4250) BN 7
J 0
(200 4260);
DISPLAY 0.617021 (200 4260);
PAINT PINK (200 4260);
FORCEPROP 2 LAST CDS_LIB mstr_standard
J 2
(200 4250);
DISPLAY 0.787234 (200 4250);
PAINT MONO (200 4250);
DISPLAY INVISIBLE (200 4250);
FORCEPROP 1 LAST BODY_TYPE PLUMBING
J 0
(200 4200);
DISPLAY 1.234043 (200 4200);
PAINT GREEN (200 4200);
DISPLAY INVISIBLE (200 4200);
FORCEPROP 1 LAST HDL_TAP TRUE
J 0
(525 4125);
DISPLAY 1.234043 (525 4125);
PAINT GREEN (525 4125);
DISPLAY INVISIBLE (525 4125);
FORCEPROP 1 LAST PATH I75
J 0
(198 4250);
DISPLAY 0.872340 (198 4250);
PAINT GREEN (198 4250);
DISPLAY INVISIBLE (198 4250);
FORCEADD TAP..6
(200 4200);
FORCEPROP 3 LASTPIN (250 4200) SIG_NAME M_D_MA<6>
J 0
(260 4210);
DISPLAY 0.659574 (260 4210);
PAINT MONO (260 4210);
DISPLAY INVISIBLE (260 4210);
FORCEPROP 1 LASTPIN (250 4200) BN 6
J 0
(200 4210);
DISPLAY 0.617021 (200 4210);
PAINT PINK (200 4210);
FORCEPROP 2 LAST CDS_LIB mstr_standard
J 2
(200 4200);
DISPLAY 0.787234 (200 4200);
PAINT MONO (200 4200);
DISPLAY INVISIBLE (200 4200);
FORCEPROP 1 LAST BODY_TYPE PLUMBING
J 0
(200 4150);
DISPLAY 1.234043 (200 4150);
PAINT GREEN (200 4150);
DISPLAY INVISIBLE (200 4150);
FORCEPROP 1 LAST HDL_TAP TRUE
J 0
(525 4075);
DISPLAY 1.234043 (525 4075);
PAINT GREEN (525 4075);
DISPLAY INVISIBLE (525 4075);
FORCEPROP 1 LAST PATH I76
J 0
(198 4200);
DISPLAY 0.872340 (198 4200);
PAINT GREEN (198 4200);
DISPLAY INVISIBLE (198 4200);
FORCEADD TAP..6
(200 4150);
FORCEPROP 3 LASTPIN (250 4150) SIG_NAME M_D_MA<5>
J 0
(260 4160);
DISPLAY 0.659574 (260 4160);
PAINT MONO (260 4160);
DISPLAY INVISIBLE (260 4160);
FORCEPROP 1 LASTPIN (250 4150) BN 5
J 0
(200 4160);
DISPLAY 0.617021 (200 4160);
PAINT PINK (200 4160);
FORCEPROP 2 LAST CDS_LIB mstr_standard
J 2
(200 4150);
DISPLAY 0.787234 (200 4150);
PAINT MONO (200 4150);
DISPLAY INVISIBLE (200 4150);
FORCEPROP 1 LAST BODY_TYPE PLUMBING
J 0
(200 4100);
DISPLAY 1.234043 (200 4100);
PAINT GREEN (200 4100);
DISPLAY INVISIBLE (200 4100);
FORCEPROP 1 LAST HDL_TAP TRUE
J 0
(525 4025);
DISPLAY 1.234043 (525 4025);
PAINT GREEN (525 4025);
DISPLAY INVISIBLE (525 4025);
FORCEPROP 1 LAST PATH I77
J 0
(198 4150);
DISPLAY 0.872340 (198 4150);
PAINT GREEN (198 4150);
DISPLAY INVISIBLE (198 4150);
FORCEADD TAP..6
(200 4100);
FORCEPROP 3 LASTPIN (250 4100) SIG_NAME M_D_MA<4>
J 0
(260 4110);
DISPLAY 0.659574 (260 4110);
PAINT MONO (260 4110);
DISPLAY INVISIBLE (260 4110);
FORCEPROP 1 LASTPIN (250 4100) BN 4
J 0
(200 4110);
DISPLAY 0.617021 (200 4110);
PAINT PINK (200 4110);
FORCEPROP 2 LAST CDS_LIB mstr_standard
J 2
(200 4100);
DISPLAY 0.787234 (200 4100);
PAINT MONO (200 4100);
DISPLAY INVISIBLE (200 4100);
FORCEPROP 1 LAST BODY_TYPE PLUMBING
J 0
(200 4050);
DISPLAY 1.234043 (200 4050);
PAINT GREEN (200 4050);
DISPLAY INVISIBLE (200 4050);
FORCEPROP 1 LAST HDL_TAP TRUE
J 0
(525 3975);
DISPLAY 1.234043 (525 3975);
PAINT GREEN (525 3975);
DISPLAY INVISIBLE (525 3975);
FORCEPROP 1 LAST PATH I78
J 0
(198 4100);
DISPLAY 0.872340 (198 4100);
PAINT GREEN (198 4100);
DISPLAY INVISIBLE (198 4100);
FORCEADD OFFPAGE..1
(-550 4800);
FORCEPROP 2 LAST $XR0 26 
J 0
(-771 4800);
DISPLAY 0.638298 (-771 4800);
PAINT MONO (-771 4800);
FORCEPROP 2 LAST $XR1 49 
J 0
(-861 4800);
DISPLAY 0.638298 (-861 4800);
PAINT MONO (-861 4800);
FORCEPROP 2 LAST CDS_LIB mstr_standard
J 0
(-550 4800);
DISPLAY 0.787234 (-550 4800);
PAINT MONO (-550 4800);
DISPLAY INVISIBLE (-550 4800);
FORCEPROP 1 LAST OFFPAGE TRUE
J 0
(-225 4675);
DISPLAY 0.936170 (-225 4675);
PAINT GREEN (-225 4675);
DISPLAY INVISIBLE (-225 4675);
FORCEPROP 1 LAST COMMENT_BODY TRUE
J 0
(-425 4700);
DISPLAY 0.936170 (-425 4700);
PAINT GREEN (-425 4700);
DISPLAY INVISIBLE (-425 4700);
FORCEPROP 2 LAST PATH I79
J 0
(-750 4850);
DISPLAY 1.021277 (-750 4850);
PAINT ORANGE (-750 4850);
DISPLAY INVISIBLE (-750 4850);
FORCEADD TAP..6
R 2
(4100 4700);
FORCEPROP 3 LASTPIN (4050 4700) SIG_NAME M_D_DQS_DP<16>
J 0
(4060 4710);
DISPLAY 0.659574 (4060 4710);
PAINT MONO (4060 4710);
DISPLAY INVISIBLE (4060 4710);
FORCEPROP 1 LASTPIN (4050 4700) BN 16
J 2
(4100 4710);
DISPLAY 0.617021 (4100 4710);
PAINT PINK (4100 4710);
FORCEPROP 2 LAST CDS_LIB mstr_standard
J 0
(4100 4700);
DISPLAY 0.787234 (4100 4700);
PAINT MONO (4100 4700);
DISPLAY INVISIBLE (4100 4700);
FORCEPROP 1 LAST BODY_TYPE PLUMBING
J 2
(4100 4650);
DISPLAY 1.234043 (4100 4650);
PAINT GREEN (4100 4650);
DISPLAY INVISIBLE (4100 4650);
FORCEPROP 1 LAST HDL_TAP TRUE
J 2
(3775 4575);
DISPLAY 1.234043 (3775 4575);
PAINT GREEN (3775 4575);
DISPLAY INVISIBLE (3775 4575);
FORCEPROP 1 LAST PATH I8
J 2
(4102 4700);
DISPLAY 0.872340 (4102 4700);
PAINT GREEN (4102 4700);
DISPLAY INVISIBLE (4102 4700);
FORCEADD TAP..6
R 2
(1700 3950);
FORCEPROP 3 LASTPIN (1650 3950) SIG_NAME M_D_DQ<47>
J 0
(1660 3960);
DISPLAY 0.659574 (1660 3960);
PAINT MONO (1660 3960);
DISPLAY INVISIBLE (1660 3960);
FORCEPROP 1 LASTPIN (1650 3950) BN 47
J 2
(1700 3960);
DISPLAY 0.617021 (1700 3960);
PAINT PINK (1700 3960);
FORCEPROP 2 LAST CDS_LIB mstr_standard
J 2
(1700 3950);
DISPLAY 0.787234 (1700 3950);
PAINT MONO (1700 3950);
DISPLAY INVISIBLE (1700 3950);
FORCEPROP 1 LAST BODY_TYPE PLUMBING
J 2
(1700 3900);
DISPLAY 1.234043 (1700 3900);
PAINT GREEN (1700 3900);
DISPLAY INVISIBLE (1700 3900);
FORCEPROP 1 LAST HDL_TAP TRUE
J 2
(1375 3825);
DISPLAY 1.234043 (1375 3825);
PAINT GREEN (1375 3825);
DISPLAY INVISIBLE (1375 3825);
FORCEPROP 1 LAST PATH I80
J 2
(1702 3950);
DISPLAY 0.872340 (1702 3950);
PAINT GREEN (1702 3950);
DISPLAY INVISIBLE (1702 3950);
FORCEADD TAP..6
R 2
(1700 3850);
FORCEPROP 3 LASTPIN (1650 3850) SIG_NAME M_D_DQ<45>
J 0
(1660 3860);
DISPLAY 0.659574 (1660 3860);
PAINT MONO (1660 3860);
DISPLAY INVISIBLE (1660 3860);
FORCEPROP 1 LASTPIN (1650 3850) BN 45
J 2
(1700 3860);
DISPLAY 0.617021 (1700 3860);
PAINT PINK (1700 3860);
FORCEPROP 2 LAST CDS_LIB mstr_standard
J 2
(1700 3850);
DISPLAY 0.787234 (1700 3850);
PAINT MONO (1700 3850);
DISPLAY INVISIBLE (1700 3850);
FORCEPROP 1 LAST BODY_TYPE PLUMBING
J 2
(1700 3800);
DISPLAY 1.234043 (1700 3800);
PAINT GREEN (1700 3800);
DISPLAY INVISIBLE (1700 3800);
FORCEPROP 1 LAST HDL_TAP TRUE
J 2
(1375 3725);
DISPLAY 1.234043 (1375 3725);
PAINT GREEN (1375 3725);
DISPLAY INVISIBLE (1375 3725);
FORCEPROP 1 LAST PATH I81
J 2
(1702 3850);
DISPLAY 0.872340 (1702 3850);
PAINT GREEN (1702 3850);
DISPLAY INVISIBLE (1702 3850);
FORCEADD TAP..6
R 2
(1700 4000);
FORCEPROP 3 LASTPIN (1650 4000) SIG_NAME M_D_DQ<48>
J 0
(1660 4010);
DISPLAY 0.659574 (1660 4010);
PAINT MONO (1660 4010);
DISPLAY INVISIBLE (1660 4010);
FORCEPROP 1 LASTPIN (1650 4000) BN 48
J 2
(1700 4010);
DISPLAY 0.617021 (1700 4010);
PAINT PINK (1700 4010);
FORCEPROP 2 LAST CDS_LIB mstr_standard
J 2
(1700 4000);
DISPLAY 0.787234 (1700 4000);
PAINT MONO (1700 4000);
DISPLAY INVISIBLE (1700 4000);
FORCEPROP 1 LAST BODY_TYPE PLUMBING
J 2
(1700 3950);
DISPLAY 1.234043 (1700 3950);
PAINT GREEN (1700 3950);
DISPLAY INVISIBLE (1700 3950);
FORCEPROP 1 LAST HDL_TAP TRUE
J 2
(1375 3875);
DISPLAY 1.234043 (1375 3875);
PAINT GREEN (1375 3875);
DISPLAY INVISIBLE (1375 3875);
FORCEPROP 1 LAST PATH I82
J 2
(1702 4000);
DISPLAY 0.872340 (1702 4000);
PAINT GREEN (1702 4000);
DISPLAY INVISIBLE (1702 4000);
FORCEADD TAP..6
R 2
(1700 4050);
FORCEPROP 3 LASTPIN (1650 4050) SIG_NAME M_D_DQ<49>
J 0
(1660 4060);
DISPLAY 0.659574 (1660 4060);
PAINT MONO (1660 4060);
DISPLAY INVISIBLE (1660 4060);
FORCEPROP 1 LASTPIN (1650 4050) BN 49
J 2
(1700 4060);
DISPLAY 0.617021 (1700 4060);
PAINT PINK (1700 4060);
FORCEPROP 2 LAST CDS_LIB mstr_standard
J 2
(1700 4050);
DISPLAY 0.787234 (1700 4050);
PAINT MONO (1700 4050);
DISPLAY INVISIBLE (1700 4050);
FORCEPROP 1 LAST BODY_TYPE PLUMBING
J 2
(1700 4000);
DISPLAY 1.234043 (1700 4000);
PAINT GREEN (1700 4000);
DISPLAY INVISIBLE (1700 4000);
FORCEPROP 1 LAST HDL_TAP TRUE
J 2
(1375 3925);
DISPLAY 1.234043 (1375 3925);
PAINT GREEN (1375 3925);
DISPLAY INVISIBLE (1375 3925);
FORCEPROP 1 LAST PATH I83
J 2
(1702 4050);
DISPLAY 0.872340 (1702 4050);
PAINT GREEN (1702 4050);
DISPLAY INVISIBLE (1702 4050);
FORCEADD TAP..6
R 2
(1700 3900);
FORCEPROP 3 LASTPIN (1650 3900) SIG_NAME M_D_DQ<46>
J 0
(1660 3910);
DISPLAY 0.659574 (1660 3910);
PAINT MONO (1660 3910);
DISPLAY INVISIBLE (1660 3910);
FORCEPROP 1 LASTPIN (1650 3900) BN 46
J 2
(1700 3910);
DISPLAY 0.617021 (1700 3910);
PAINT PINK (1700 3910);
FORCEPROP 2 LAST CDS_LIB mstr_standard
J 2
(1700 3900);
DISPLAY 0.787234 (1700 3900);
PAINT MONO (1700 3900);
DISPLAY INVISIBLE (1700 3900);
FORCEPROP 1 LAST BODY_TYPE PLUMBING
J 2
(1700 3850);
DISPLAY 1.234043 (1700 3850);
PAINT GREEN (1700 3850);
DISPLAY INVISIBLE (1700 3850);
FORCEPROP 1 LAST HDL_TAP TRUE
J 2
(1375 3775);
DISPLAY 1.234043 (1375 3775);
PAINT GREEN (1375 3775);
DISPLAY INVISIBLE (1375 3775);
FORCEPROP 1 LAST PATH I84
J 2
(1702 3900);
DISPLAY 0.872340 (1702 3900);
PAINT GREEN (1702 3900);
DISPLAY INVISIBLE (1702 3900);
FORCEADD TAP..6
R 2
(1700 3700);
FORCEPROP 3 LASTPIN (1650 3700) SIG_NAME M_D_DQ<42>
J 0
(1660 3710);
DISPLAY 0.659574 (1660 3710);
PAINT MONO (1660 3710);
DISPLAY INVISIBLE (1660 3710);
FORCEPROP 1 LASTPIN (1650 3700) BN 42
J 2
(1700 3710);
DISPLAY 0.617021 (1700 3710);
PAINT PINK (1700 3710);
FORCEPROP 2 LAST CDS_LIB mstr_standard
J 2
(1700 3700);
DISPLAY 0.787234 (1700 3700);
PAINT MONO (1700 3700);
DISPLAY INVISIBLE (1700 3700);
FORCEPROP 1 LAST BODY_TYPE PLUMBING
J 2
(1700 3650);
DISPLAY 1.234043 (1700 3650);
PAINT GREEN (1700 3650);
DISPLAY INVISIBLE (1700 3650);
FORCEPROP 1 LAST HDL_TAP TRUE
J 2
(1375 3575);
DISPLAY 1.234043 (1375 3575);
PAINT GREEN (1375 3575);
DISPLAY INVISIBLE (1375 3575);
FORCEPROP 1 LAST PATH I85
J 2
(1702 3700);
DISPLAY 0.872340 (1702 3700);
PAINT GREEN (1702 3700);
DISPLAY INVISIBLE (1702 3700);
FORCEADD TAP..6
R 2
(1700 3750);
FORCEPROP 3 LASTPIN (1650 3750) SIG_NAME M_D_DQ<43>
J 0
(1660 3760);
DISPLAY 0.659574 (1660 3760);
PAINT MONO (1660 3760);
DISPLAY INVISIBLE (1660 3760);
FORCEPROP 1 LASTPIN (1650 3750) BN 43
J 2
(1700 3760);
DISPLAY 0.617021 (1700 3760);
PAINT PINK (1700 3760);
FORCEPROP 2 LAST CDS_LIB mstr_standard
J 2
(1700 3750);
DISPLAY 0.787234 (1700 3750);
PAINT MONO (1700 3750);
DISPLAY INVISIBLE (1700 3750);
FORCEPROP 1 LAST BODY_TYPE PLUMBING
J 2
(1700 3700);
DISPLAY 1.234043 (1700 3700);
PAINT GREEN (1700 3700);
DISPLAY INVISIBLE (1700 3700);
FORCEPROP 1 LAST HDL_TAP TRUE
J 2
(1375 3625);
DISPLAY 1.234043 (1375 3625);
PAINT GREEN (1375 3625);
DISPLAY INVISIBLE (1375 3625);
FORCEPROP 1 LAST PATH I86
J 2
(1702 3750);
DISPLAY 0.872340 (1702 3750);
PAINT GREEN (1702 3750);
DISPLAY INVISIBLE (1702 3750);
FORCEADD TAP..6
R 2
(1700 3800);
FORCEPROP 3 LASTPIN (1650 3800) SIG_NAME M_D_DQ<44>
J 0
(1660 3810);
DISPLAY 0.659574 (1660 3810);
PAINT MONO (1660 3810);
DISPLAY INVISIBLE (1660 3810);
FORCEPROP 1 LASTPIN (1650 3800) BN 44
J 2
(1700 3810);
DISPLAY 0.617021 (1700 3810);
PAINT PINK (1700 3810);
FORCEPROP 2 LAST CDS_LIB mstr_standard
J 2
(1700 3800);
DISPLAY 0.787234 (1700 3800);
PAINT MONO (1700 3800);
DISPLAY INVISIBLE (1700 3800);
FORCEPROP 1 LAST BODY_TYPE PLUMBING
J 2
(1700 3750);
DISPLAY 1.234043 (1700 3750);
PAINT GREEN (1700 3750);
DISPLAY INVISIBLE (1700 3750);
FORCEPROP 1 LAST HDL_TAP TRUE
J 2
(1375 3675);
DISPLAY 1.234043 (1375 3675);
PAINT GREEN (1375 3675);
DISPLAY INVISIBLE (1375 3675);
FORCEPROP 1 LAST PATH I87
J 2
(1702 3800);
DISPLAY 0.872340 (1702 3800);
PAINT GREEN (1702 3800);
DISPLAY INVISIBLE (1702 3800);
FORCEADD TAP..6
R 2
(1700 3650);
FORCEPROP 3 LASTPIN (1650 3650) SIG_NAME M_D_DQ<41>
J 0
(1660 3660);
DISPLAY 0.659574 (1660 3660);
PAINT MONO (1660 3660);
DISPLAY INVISIBLE (1660 3660);
FORCEPROP 1 LASTPIN (1650 3650) BN 41
J 2
(1700 3660);
DISPLAY 0.617021 (1700 3660);
PAINT PINK (1700 3660);
FORCEPROP 2 LAST CDS_LIB mstr_standard
J 2
(1700 3650);
DISPLAY 0.787234 (1700 3650);
PAINT MONO (1700 3650);
DISPLAY INVISIBLE (1700 3650);
FORCEPROP 1 LAST BODY_TYPE PLUMBING
J 2
(1700 3600);
DISPLAY 1.234043 (1700 3600);
PAINT GREEN (1700 3600);
DISPLAY INVISIBLE (1700 3600);
FORCEPROP 1 LAST HDL_TAP TRUE
J 2
(1375 3525);
DISPLAY 1.234043 (1375 3525);
PAINT GREEN (1375 3525);
DISPLAY INVISIBLE (1375 3525);
FORCEPROP 1 LAST PATH I88
J 2
(1702 3650);
DISPLAY 0.872340 (1702 3650);
PAINT GREEN (1702 3650);
DISPLAY INVISIBLE (1702 3650);
FORCEADD TAP..6
R 2
(1700 3600);
FORCEPROP 3 LASTPIN (1650 3600) SIG_NAME M_D_DQ<40>
J 0
(1660 3610);
DISPLAY 0.659574 (1660 3610);
PAINT MONO (1660 3610);
DISPLAY INVISIBLE (1660 3610);
FORCEPROP 1 LASTPIN (1650 3600) BN 40
J 2
(1700 3610);
DISPLAY 0.617021 (1700 3610);
PAINT PINK (1700 3610);
FORCEPROP 2 LAST CDS_LIB mstr_standard
J 2
(1700 3600);
DISPLAY 0.787234 (1700 3600);
PAINT MONO (1700 3600);
DISPLAY INVISIBLE (1700 3600);
FORCEPROP 1 LAST BODY_TYPE PLUMBING
J 2
(1700 3550);
DISPLAY 1.234043 (1700 3550);
PAINT GREEN (1700 3550);
DISPLAY INVISIBLE (1700 3550);
FORCEPROP 1 LAST HDL_TAP TRUE
J 2
(1375 3475);
DISPLAY 1.234043 (1375 3475);
PAINT GREEN (1375 3475);
DISPLAY INVISIBLE (1375 3475);
FORCEPROP 1 LAST PATH I89
J 2
(1702 3600);
DISPLAY 0.872340 (1702 3600);
PAINT GREEN (1702 3600);
DISPLAY INVISIBLE (1702 3600);
FORCEADD TAP..6
R 2
(4350 4550);
FORCEPROP 3 LASTPIN (4300 4550) SIG_NAME M_D_DQS_DN<15>
J 0
(4310 4560);
DISPLAY 0.659574 (4310 4560);
PAINT MONO (4310 4560);
DISPLAY INVISIBLE (4310 4560);
FORCEPROP 1 LASTPIN (4300 4550) BN 15
J 2
(4350 4560);
DISPLAY 0.617021 (4350 4560);
PAINT PINK (4350 4560);
FORCEPROP 2 LAST CDS_LIB mstr_standard
J 0
(4350 4550);
DISPLAY 0.787234 (4350 4550);
PAINT MONO (4350 4550);
DISPLAY INVISIBLE (4350 4550);
FORCEPROP 1 LAST BODY_TYPE PLUMBING
J 2
(4350 4500);
DISPLAY 1.234043 (4350 4500);
PAINT GREEN (4350 4500);
DISPLAY INVISIBLE (4350 4500);
FORCEPROP 1 LAST HDL_TAP TRUE
J 2
(4025 4425);
DISPLAY 1.234043 (4025 4425);
PAINT GREEN (4025 4425);
DISPLAY INVISIBLE (4025 4425);
FORCEPROP 1 LAST PATH I9
J 2
(4352 4550);
DISPLAY 0.872340 (4352 4550);
PAINT GREEN (4352 4550);
DISPLAY INVISIBLE (4352 4550);
FORCEADD TAP..6
R 2
(1700 3350);
FORCEPROP 3 LASTPIN (1650 3350) SIG_NAME M_D_DQ<35>
J 0
(1660 3360);
DISPLAY 0.659574 (1660 3360);
PAINT MONO (1660 3360);
DISPLAY INVISIBLE (1660 3360);
FORCEPROP 1 LASTPIN (1650 3350) BN 35
J 2
(1700 3360);
DISPLAY 0.617021 (1700 3360);
PAINT PINK (1700 3360);
FORCEPROP 2 LAST CDS_LIB mstr_standard
J 2
(1700 3350);
DISPLAY 0.787234 (1700 3350);
PAINT MONO (1700 3350);
DISPLAY INVISIBLE (1700 3350);
FORCEPROP 1 LAST BODY_TYPE PLUMBING
J 2
(1700 3300);
DISPLAY 1.234043 (1700 3300);
PAINT GREEN (1700 3300);
DISPLAY INVISIBLE (1700 3300);
FORCEPROP 1 LAST HDL_TAP TRUE
J 2
(1375 3225);
DISPLAY 1.234043 (1375 3225);
PAINT GREEN (1375 3225);
DISPLAY INVISIBLE (1375 3225);
FORCEPROP 1 LAST PATH I90
J 2
(1702 3350);
DISPLAY 0.872340 (1702 3350);
PAINT GREEN (1702 3350);
DISPLAY INVISIBLE (1702 3350);
FORCEADD TAP..6
R 2
(1700 3400);
FORCEPROP 3 LASTPIN (1650 3400) SIG_NAME M_D_DQ<36>
J 0
(1660 3410);
DISPLAY 0.659574 (1660 3410);
PAINT MONO (1660 3410);
DISPLAY INVISIBLE (1660 3410);
FORCEPROP 1 LASTPIN (1650 3400) BN 36
J 2
(1700 3410);
DISPLAY 0.617021 (1700 3410);
PAINT PINK (1700 3410);
FORCEPROP 2 LAST CDS_LIB mstr_standard
J 2
(1700 3400);
DISPLAY 0.787234 (1700 3400);
PAINT MONO (1700 3400);
DISPLAY INVISIBLE (1700 3400);
FORCEPROP 1 LAST BODY_TYPE PLUMBING
J 2
(1700 3350);
DISPLAY 1.234043 (1700 3350);
PAINT GREEN (1700 3350);
DISPLAY INVISIBLE (1700 3350);
FORCEPROP 1 LAST HDL_TAP TRUE
J 2
(1375 3275);
DISPLAY 1.234043 (1375 3275);
PAINT GREEN (1375 3275);
DISPLAY INVISIBLE (1375 3275);
FORCEPROP 1 LAST PATH I91
J 2
(1702 3400);
DISPLAY 0.872340 (1702 3400);
PAINT GREEN (1702 3400);
DISPLAY INVISIBLE (1702 3400);
FORCEADD TAP..6
R 2
(1700 3500);
FORCEPROP 3 LASTPIN (1650 3500) SIG_NAME M_D_DQ<38>
J 0
(1660 3510);
DISPLAY 0.659574 (1660 3510);
PAINT MONO (1660 3510);
DISPLAY INVISIBLE (1660 3510);
FORCEPROP 1 LASTPIN (1650 3500) BN 38
J 2
(1700 3510);
DISPLAY 0.617021 (1700 3510);
PAINT PINK (1700 3510);
FORCEPROP 2 LAST CDS_LIB mstr_standard
J 2
(1700 3500);
DISPLAY 0.787234 (1700 3500);
PAINT MONO (1700 3500);
DISPLAY INVISIBLE (1700 3500);
FORCEPROP 1 LAST BODY_TYPE PLUMBING
J 2
(1700 3450);
DISPLAY 1.234043 (1700 3450);
PAINT GREEN (1700 3450);
DISPLAY INVISIBLE (1700 3450);
FORCEPROP 1 LAST HDL_TAP TRUE
J 2
(1375 3375);
DISPLAY 1.234043 (1375 3375);
PAINT GREEN (1375 3375);
DISPLAY INVISIBLE (1375 3375);
FORCEPROP 1 LAST PATH I92
J 2
(1702 3500);
DISPLAY 0.872340 (1702 3500);
PAINT GREEN (1702 3500);
DISPLAY INVISIBLE (1702 3500);
FORCEADD TAP..6
R 2
(1700 3450);
FORCEPROP 3 LASTPIN (1650 3450) SIG_NAME M_D_DQ<37>
J 0
(1660 3460);
DISPLAY 0.659574 (1660 3460);
PAINT MONO (1660 3460);
DISPLAY INVISIBLE (1660 3460);
FORCEPROP 1 LASTPIN (1650 3450) BN 37
J 2
(1700 3460);
DISPLAY 0.617021 (1700 3460);
PAINT PINK (1700 3460);
FORCEPROP 2 LAST CDS_LIB mstr_standard
J 2
(1700 3450);
DISPLAY 0.787234 (1700 3450);
PAINT MONO (1700 3450);
DISPLAY INVISIBLE (1700 3450);
FORCEPROP 1 LAST BODY_TYPE PLUMBING
J 2
(1700 3400);
DISPLAY 1.234043 (1700 3400);
PAINT GREEN (1700 3400);
DISPLAY INVISIBLE (1700 3400);
FORCEPROP 1 LAST HDL_TAP TRUE
J 2
(1375 3325);
DISPLAY 1.234043 (1375 3325);
PAINT GREEN (1375 3325);
DISPLAY INVISIBLE (1375 3325);
FORCEPROP 1 LAST PATH I93
J 2
(1702 3450);
DISPLAY 0.872340 (1702 3450);
PAINT GREEN (1702 3450);
DISPLAY INVISIBLE (1702 3450);
FORCEADD TAP..6
R 2
(1700 3550);
FORCEPROP 3 LASTPIN (1650 3550) SIG_NAME M_D_DQ<39>
J 0
(1660 3560);
DISPLAY 0.659574 (1660 3560);
PAINT MONO (1660 3560);
DISPLAY INVISIBLE (1660 3560);
FORCEPROP 1 LASTPIN (1650 3550) BN 39
J 2
(1700 3560);
DISPLAY 0.617021 (1700 3560);
PAINT PINK (1700 3560);
FORCEPROP 2 LAST CDS_LIB mstr_standard
J 2
(1700 3550);
DISPLAY 0.787234 (1700 3550);
PAINT MONO (1700 3550);
DISPLAY INVISIBLE (1700 3550);
FORCEPROP 1 LAST BODY_TYPE PLUMBING
J 2
(1700 3500);
DISPLAY 1.234043 (1700 3500);
PAINT GREEN (1700 3500);
DISPLAY INVISIBLE (1700 3500);
FORCEPROP 1 LAST HDL_TAP TRUE
J 2
(1375 3425);
DISPLAY 1.234043 (1375 3425);
PAINT GREEN (1375 3425);
DISPLAY INVISIBLE (1375 3425);
FORCEPROP 1 LAST PATH I94
J 2
(1702 3550);
DISPLAY 0.872340 (1702 3550);
PAINT GREEN (1702 3550);
DISPLAY INVISIBLE (1702 3550);
FORCEADD TAP..6
R 2
(1700 3200);
FORCEPROP 3 LASTPIN (1650 3200) SIG_NAME M_D_DQ<32>
J 0
(1660 3210);
DISPLAY 0.659574 (1660 3210);
PAINT MONO (1660 3210);
DISPLAY INVISIBLE (1660 3210);
FORCEPROP 1 LASTPIN (1650 3200) BN 32
J 2
(1700 3210);
DISPLAY 0.617021 (1700 3210);
PAINT PINK (1700 3210);
FORCEPROP 2 LAST CDS_LIB mstr_standard
J 2
(1700 3200);
DISPLAY 0.787234 (1700 3200);
PAINT MONO (1700 3200);
DISPLAY INVISIBLE (1700 3200);
FORCEPROP 1 LAST BODY_TYPE PLUMBING
J 2
(1700 3150);
DISPLAY 1.234043 (1700 3150);
PAINT GREEN (1700 3150);
DISPLAY INVISIBLE (1700 3150);
FORCEPROP 1 LAST HDL_TAP TRUE
J 2
(1375 3075);
DISPLAY 1.234043 (1375 3075);
PAINT GREEN (1375 3075);
DISPLAY INVISIBLE (1375 3075);
FORCEPROP 1 LAST PATH I95
J 2
(1702 3200);
DISPLAY 0.872340 (1702 3200);
PAINT GREEN (1702 3200);
DISPLAY INVISIBLE (1702 3200);
FORCEADD TAP..6
R 2
(1700 3250);
FORCEPROP 3 LASTPIN (1650 3250) SIG_NAME M_D_DQ<33>
J 0
(1660 3260);
DISPLAY 0.659574 (1660 3260);
PAINT MONO (1660 3260);
DISPLAY INVISIBLE (1660 3260);
FORCEPROP 1 LASTPIN (1650 3250) BN 33
J 2
(1700 3260);
DISPLAY 0.617021 (1700 3260);
PAINT PINK (1700 3260);
FORCEPROP 2 LAST CDS_LIB mstr_standard
J 2
(1700 3250);
DISPLAY 0.787234 (1700 3250);
PAINT MONO (1700 3250);
DISPLAY INVISIBLE (1700 3250);
FORCEPROP 1 LAST BODY_TYPE PLUMBING
J 2
(1700 3200);
DISPLAY 1.234043 (1700 3200);
PAINT GREEN (1700 3200);
DISPLAY INVISIBLE (1700 3200);
FORCEPROP 1 LAST HDL_TAP TRUE
J 2
(1375 3125);
DISPLAY 1.234043 (1375 3125);
PAINT GREEN (1375 3125);
DISPLAY INVISIBLE (1375 3125);
FORCEPROP 1 LAST PATH I96
J 2
(1702 3250);
DISPLAY 0.872340 (1702 3250);
PAINT GREEN (1702 3250);
DISPLAY INVISIBLE (1702 3250);
FORCEADD TAP..6
R 2
(1700 3300);
FORCEPROP 3 LASTPIN (1650 3300) SIG_NAME M_D_DQ<34>
J 0
(1660 3310);
DISPLAY 0.659574 (1660 3310);
PAINT MONO (1660 3310);
DISPLAY INVISIBLE (1660 3310);
FORCEPROP 1 LASTPIN (1650 3300) BN 34
J 2
(1700 3310);
DISPLAY 0.617021 (1700 3310);
PAINT PINK (1700 3310);
FORCEPROP 2 LAST CDS_LIB mstr_standard
J 2
(1700 3300);
DISPLAY 0.787234 (1700 3300);
PAINT MONO (1700 3300);
DISPLAY INVISIBLE (1700 3300);
FORCEPROP 1 LAST BODY_TYPE PLUMBING
J 2
(1700 3250);
DISPLAY 1.234043 (1700 3250);
PAINT GREEN (1700 3250);
DISPLAY INVISIBLE (1700 3250);
FORCEPROP 1 LAST HDL_TAP TRUE
J 2
(1375 3175);
DISPLAY 1.234043 (1375 3175);
PAINT GREEN (1375 3175);
DISPLAY INVISIBLE (1375 3175);
FORCEPROP 1 LAST PATH I97
J 2
(1702 3300);
DISPLAY 0.872340 (1702 3300);
PAINT GREEN (1702 3300);
DISPLAY INVISIBLE (1702 3300);
FORCEADD TAP..6
R 2
(1700 3100);
FORCEPROP 3 LASTPIN (1650 3100) SIG_NAME M_D_DQ<30>
J 0
(1660 3110);
DISPLAY 0.659574 (1660 3110);
PAINT MONO (1660 3110);
DISPLAY INVISIBLE (1660 3110);
FORCEPROP 1 LASTPIN (1650 3100) BN 30
J 2
(1700 3110);
DISPLAY 0.617021 (1700 3110);
PAINT PINK (1700 3110);
FORCEPROP 2 LAST CDS_LIB mstr_standard
J 2
(1700 3100);
DISPLAY 0.787234 (1700 3100);
PAINT MONO (1700 3100);
DISPLAY INVISIBLE (1700 3100);
FORCEPROP 1 LAST BODY_TYPE PLUMBING
J 2
(1700 3050);
DISPLAY 1.234043 (1700 3050);
PAINT GREEN (1700 3050);
DISPLAY INVISIBLE (1700 3050);
FORCEPROP 1 LAST HDL_TAP TRUE
J 2
(1375 2975);
DISPLAY 1.234043 (1375 2975);
PAINT GREEN (1375 2975);
DISPLAY INVISIBLE (1375 2975);
FORCEPROP 1 LAST PATH I98
J 2
(1702 3100);
DISPLAY 0.872340 (1702 3100);
PAINT GREEN (1702 3100);
DISPLAY INVISIBLE (1702 3100);
FORCEADD TAP..6
R 2
(1700 3150);
FORCEPROP 3 LASTPIN (1650 3150) SIG_NAME M_D_DQ<31>
J 0
(1660 3160);
DISPLAY 0.659574 (1660 3160);
PAINT MONO (1660 3160);
DISPLAY INVISIBLE (1660 3160);
FORCEPROP 1 LASTPIN (1650 3150) BN 31
J 2
(1700 3160);
DISPLAY 0.617021 (1700 3160);
PAINT PINK (1700 3160);
FORCEPROP 2 LAST CDS_LIB mstr_standard
J 2
(1700 3150);
DISPLAY 0.787234 (1700 3150);
PAINT MONO (1700 3150);
DISPLAY INVISIBLE (1700 3150);
FORCEPROP 1 LAST BODY_TYPE PLUMBING
J 2
(1700 3100);
DISPLAY 1.234043 (1700 3100);
PAINT GREEN (1700 3100);
DISPLAY INVISIBLE (1700 3100);
FORCEPROP 1 LAST HDL_TAP TRUE
J 2
(1375 3025);
DISPLAY 1.234043 (1375 3025);
PAINT GREEN (1375 3025);
DISPLAY INVISIBLE (1375 3025);
FORCEPROP 1 LAST PATH I99
J 2
(1702 3150);
DISPLAY 0.872340 (1702 3150);
PAINT GREEN (1702 3150);
DISPLAY INVISIBLE (1702 3150);
FORCEADD BOM_NOTE..1
(-1650 4975);
FORCEPROP 0 LAST L1 UNSTUFF FOR SKU B
J 0
(-1800 4875);
DISPLAY 1.063830 (-1800 4875);
PAINT WHITE (-1800 4875);
FORCEPROP 2 LAST BOM_COST SB
J 0
(-1800 4950);
DISPLAY 1.361702 (-1800 4950);
PAINT ORANGE (-1800 4950);
DISPLAY INVISIBLE (-1800 4950);
FORCEPROP 2 LAST CDS_LIB mstr_symbols
J 0
(-1650 4975);
PAINT ORANGE (-1650 4975);
DISPLAY INVISIBLE (-1650 4975);
FORCEPROP 1 LAST COMMENT_BODY TRUE
J 0
(-1625 5075);
DISPLAY 1.319149 (-1625 5075);
PAINT ORANGE (-1625 5075);
DISPLAY INVISIBLE (-1625 5075);
FORCEPROP 2 LAST ROOM SB_HEADERS
J 0
(-1800 4950);
DISPLAY 1.361702 (-1800 4950);
PAINT ORANGE (-1800 4950);
DISPLAY INVISIBLE (-1800 4950);
FORCEADD INTEL_CORP_BPAGE..1
(6075 175);
FORCEPROP 1 LAST CDS_CON_LAST_MODIFIED Tue Dec 01 11:51:30 2015
J 0
(4650 500);
PAINT ORANGE (4650 500);
DISPLAY INVISIBLE (4650 500);
FORCEPROP 1 LAST CUSTOM_TXT_CDS <CURRENT_DESIGN_SHEET> OF <TOTAL_DESIGN_SHEETS>
J 0
(5575 200);
PAINT GREEN (5575 200);
FORCEPROP 1 LAST CUSTOM_TXT_CDS <CON_LAST_MODIFIED>
J 0
(4150 525);
PAINT GREEN (4150 525);
FORCEPROP 2 LAST CUSTOM_TXT_CDS <XR_PAGE_TITLE>
J 0
(-1815 5425);
DISPLAY 0.638298 (-1815 5425);
PAINT PINK (-1815 5425);
DISPLAY INVISIBLE (-1815 5425);
FORCEPROP 1 LAST SCH_ADDRESS3 Santa Clara, CA 95052-8119
J 0
(2100 200);
DISPLAY 0.617021 (2100 200);
PAINT GREEN (2100 200);
FORCEPROP 1 LAST SCH_ADDRESS2 P.O. BOX 58119
J 0
(2100 250);
DISPLAY 0.617021 (2100 250);
PAINT GREEN (2100 250);
FORCEPROP 1 LAST SCH_ADDRESS1 2200 Mission College Blvd.
J 0
(2100 300);
DISPLAY 0.617021 (2100 300);
PAINT GREEN (2100 300);
FORCEPROP 1 LAST SCH_TITLE CPU0 DDR4 CH D DIMM1
J 0
(-1875 225);
DISPLAY 1.212766 (-1875 225);
PAINT ORANGE (-1875 225);
FORCEPROP 1 LAST SCH_NUMBER H4694802
J 0
(4775 325);
DISPLAY 1.212766 (4775 325);
PAINT YELLOW (4775 325);
FORCEPROP 1 LAST SCH_DEPT BESD
J 1
(1625 275);
DISPLAY 1.212766 (1625 275);
PAINT YELLOW (1625 275);
FORCEPROP 1 LAST SCH_REV 2.420
J 0
(5825 325);
DISPLAY 0.978723 (5825 325);
PAINT YELLOW (5825 325);
FORCEPROP 2 LAST CDS_LIB mstr_symbols
J 0
(6075 175);
PAINT MONO (6075 175);
DISPLAY INVISIBLE (6075 175);
FORCEPROP 2 LAST PAGE_BORDER TRUE
J 0
(-1815 5425);
DISPLAY 0.638298 (-1815 5425);
PAINT PINK (-1815 5425);
DISPLAY INVISIBLE (-1815 5425);
FORCEPROP 1 LAST COMMENT_BODY TRUE
J 0
(6087 187);
DISPLAY 0.468085 (6087 187);
PAINT GREEN (6087 187);
DISPLAY INVISIBLE (6087 187);
FORCEPROP 2 LAST CDS_XR_PAGE_TITLE CR-50 : @BASEBOARD_FAB2_LIB.BASEBOARD_FAB2(SCH_1):PAGE50
J 0
(-1815 5425);
DISPLAY 0.638298 (-1815 5425);
PAINT PINK (-1815 5425);
DISPLAY INVISIBLE (-1815 5425);
WIRE 17 -1 (4400 3875)(4400 3975);
WIRE 17 -1 (4400 3775)(4400 3875);
WIRE 17 -1 (4400 3975)(4400 4075);
WIRE 17 -1 (4400 4075)(4400 4175);
WIRE 17 -1 (4400 3675)(4400 3775);
WIRE 17 -1 (4400 3575)(4400 3675);
WIRE 17 -1 (4400 4175)(4400 4275);
WIRE 17 -1 (4400 4275)(4400 4375);
WIRE 17 -1 (4400 3475)(4400 3575);
WIRE 17 -1 (4400 3375)(4400 3475);
WIRE 17 -1 (4400 4375)(4400 4475);
WIRE 17 -1 (4400 4475)(4400 4575);
WIRE 17 -1 (4400 3275)(4400 3375);
WIRE 17 -1 (4400 3175)(4400 3275);
WIRE 17 -1 (4400 4575)(4400 4675);
WIRE 17 -1 (4400 4675)(4400 4775);
WIRE 17 -1 (4400 3075)(4400 3175);
WIRE 17 -1 (4400 4775)(4400 4800);
WIRE 17 -1 (5050 4800)(4400 4800);
FORCEPROP 2 LAST SIG_NAME M_D_DQS_DN<17:0>
J 0
(4450 4810);
DISPLAY 0.617021 (4450 4810);
PAINT ORANGE (4450 4810);
WIRE 17 -1 (4150 4725)(4150 4825);
WIRE 17 -1 (4150 4625)(4150 4725);
WIRE 17 -1 (4150 4825)(4150 4850);
WIRE 17 -1 (5050 4850)(4150 4850);
FORCEPROP 2 LAST SIG_NAME M_D_DQS_DP<17:0>
J 0
(4450 4860);
DISPLAY 0.617021 (4450 4860);
PAINT ORANGE (4450 4860);
WIRE 17 -1 (4150 4525)(4150 4625);
WIRE 17 -1 (4150 4425)(4150 4525);
WIRE 17 -1 (4150 4325)(4150 4425);
WIRE 17 -1 (4150 4225)(4150 4325);
WIRE 17 -1 (4150 4125)(4150 4225);
WIRE 17 -1 (4150 4025)(4150 4125);
WIRE 17 -1 (4150 3925)(4150 4025);
WIRE 17 -1 (4150 3825)(4150 3925);
WIRE 17 -1 (4150 3725)(4150 3825);
WIRE 17 -1 (4150 3625)(4150 3725);
WIRE 17 -1 (4150 3525)(4150 3625);
WIRE 17 -1 (4150 3425)(4150 3525);
WIRE 17 -1 (1750 4075)(1750 4125);
WIRE 17 -1 (1750 4025)(1750 4075);
WIRE 17 -1 (1750 4125)(1750 4175);
WIRE 17 -1 (1750 4175)(1750 4225);
WIRE 17 -1 (1750 3975)(1750 4025);
WIRE 17 -1 (1750 3925)(1750 3975);
WIRE 17 -1 (1750 4225)(1750 4275);
WIRE 17 -1 (1750 4275)(1750 4325);
WIRE 17 -1 (1750 3875)(1750 3925);
WIRE 17 -1 (1750 3825)(1750 3875);
WIRE 17 -1 (1750 4325)(1750 4375);
WIRE 17 -1 (1750 4375)(1750 4425);
WIRE 17 -1 (1750 3775)(1750 3825);
WIRE 17 -1 (1750 3725)(1750 3775);
WIRE 17 -1 (1750 4425)(1750 4475);
WIRE 17 -1 (1750 4475)(1750 4525);
WIRE 17 -1 (1750 3675)(1750 3725);
WIRE 17 -1 (1750 3625)(1750 3675);
WIRE 17 -1 (1750 4525)(1750 4575);
WIRE 17 -1 (1750 4575)(1750 4625);
WIRE 17 -1 (1750 3575)(1750 3625);
WIRE 17 -1 (1750 3525)(1750 3575);
WIRE 17 -1 (1750 4625)(1750 4675);
WIRE 17 -1 (1750 4675)(1750 4725);
WIRE 17 -1 (1750 3475)(1750 3525);
WIRE 17 -1 (1750 3425)(1750 3475);
WIRE 17 -1 (1750 4725)(1750 4775);
WIRE 17 -1 (1750 4775)(1750 4800);
WIRE 17 -1 (1750 3375)(1750 3425);
WIRE 17 -1 (1750 3325)(1750 3375);
WIRE 17 -1 (2200 4800)(1750 4800);
FORCEPROP 2 LAST SIG_NAME M_D_DQ<63:0>
J 0
(1790 4810);
DISPLAY 0.617021 (1790 4810);
PAINT ORANGE (1790 4810);
WIRE 17 -1 (150 4675)(150 4725);
WIRE 17 -1 (150 4625)(150 4675);
WIRE 17 -1 (150 4725)(150 4775);
WIRE 17 -1 (150 4775)(150 4800);
WIRE 17 -1 (150 4575)(150 4625);
WIRE 17 -1 (150 4525)(150 4575);
WIRE 17 -1 (-500 4800)(150 4800);
FORCEPROP 2 LAST SIG_NAME M_D_MA<17:0>
J 0
(-475 4810);
DISPLAY 0.617021 (-475 4810);
PAINT ORANGE (-475 4810);
WIRE 17 -1 (150 4475)(150 4525);
WIRE 17 -1 (150 4425)(150 4475);
WIRE 17 -1 (150 4375)(150 4425);
WIRE 17 -1 (150 4325)(150 4375);
WIRE 17 -1 (150 4275)(150 4325);
WIRE 17 -1 (150 4225)(150 4275);
WIRE 17 -1 (150 4175)(150 4225);
WIRE 17 -1 (150 4125)(150 4175);
WIRE 17 -1 (150 4075)(150 4125);
WIRE 17 -1 (150 4025)(150 4075);
WIRE 17 -1 (150 3975)(150 4025);
WIRE 17 -1 (150 3925)(150 3975);
WIRE 17 -1 (4150 3325)(4150 3425);
WIRE 17 -1 (4150 3225)(4150 3325);
WIRE 17 -1 (4150 3125)(4150 3225);
WIRE 17 -1 (1750 3275)(1750 3325);
WIRE 17 -1 (1750 3225)(1750 3275);
WIRE 17 -1 (1750 3175)(1750 3225);
WIRE 17 -1 (1750 3125)(1750 3175);
WIRE 17 -1 (1750 3075)(1750 3125);
WIRE 17 -1 (1750 3025)(1750 3075);
WIRE 17 -1 (1750 2975)(1750 3025);
WIRE 17 -1 (1750 2925)(1750 2975);
WIRE 17 -1 (1750 2875)(1750 2925);
WIRE 17 -1 (1750 2825)(1750 2875);
WIRE 17 -1 (1750 2775)(1750 2825);
WIRE 17 -1 (1750 2725)(1750 2775);
WIRE 17 -1 (1750 2675)(1750 2725);
WIRE 17 -1 (1750 2625)(1750 2675);
WIRE 17 -1 (1750 2575)(1750 2625);
WIRE 17 -1 (1750 2525)(1750 2575);
WIRE 17 -1 (1750 2475)(1750 2525);
WIRE 17 -1 (1750 2425)(1750 2475);
WIRE 17 -1 (1750 2375)(1750 2425);
WIRE 17 -1 (1750 2325)(1750 2375);
WIRE 17 -1 (1750 2275)(1750 2325);
WIRE 17 -1 (1750 2225)(1750 2275);
WIRE 17 -1 (1750 2175)(1750 2225);
WIRE 17 -1 (1750 2125)(1750 2175);
WIRE 17 -1 (1750 2075)(1750 2125);
WIRE 17 -1 (1750 2025)(1750 2075);
WIRE 17 -1 (1750 1975)(1750 2025);
WIRE 17 -1 (1750 1925)(1750 1975);
WIRE 17 -1 (1750 1875)(1750 1925);
WIRE 17 -1 (1750 1825)(1750 1875);
WIRE 17 -1 (1750 1775)(1750 1825);
WIRE 17 -1 (1750 1725)(1750 1775);
WIRE 17 -1 (1750 1675)(1750 1725);
WIRE 17 -1 (1750 1625)(1750 1675);
WIRE 17 -1 (150 3775)(150 3825);
WIRE 17 -1 (150 3850)(150 3825);
WIRE 17 -1 (150 3850)(-500 3850);
FORCEPROP 2 LAST SIG_NAME M_D_BA<1:0>
J 0
(-475 3860);
DISPLAY 0.617021 (-475 3860);
PAINT ORANGE (-475 3860);
WIRE 17 -1 (150 3675)(150 3725);
WIRE 17 -1 (150 3750)(150 3725);
WIRE 17 -1 (-500 3750)(150 3750);
FORCEPROP 2 LAST SIG_NAME M_D_BG<1:0>
J 0
(-475 3760);
DISPLAY 0.617021 (-475 3760);
PAINT ORANGE (-475 3760);
WIRE 17 -1 (150 3125)(150 3175);
WIRE 17 -1 (150 3175)(150 3225);
WIRE 17 -1 (150 3225)(150 3275);
WIRE 17 -1 (150 3300)(150 3275);
WIRE 17 -1 (150 3300)(-500 3300);
FORCEPROP 2 LAST SIG_NAME M_D_CS_N<7:0>
J 0
(-476 3316);
DISPLAY 0.617021 (-476 3316);
PAINT ORANGE (-476 3316);
WIRE 17 -1 (150 3475)(150 3575);
WIRE 17 -1 (150 3600)(150 3575);
WIRE 17 -1 (150 3600)(-500 3600);
FORCEPROP 2 LAST SIG_NAME M_D_CLK_DP<3:0>
J 0
(-450 3610);
DISPLAY 0.617021 (-450 3610);
PAINT ORANGE (-450 3610);
WIRE 17 -1 (-50 3525)(-50 3425);
WIRE 17 -1 (-50 3550)(-50 3525);
WIRE 17 -1 (-50 3550)(-500 3550);
FORCEPROP 2 LAST SIG_NAME M_D_CLK_DN<3:0>
J 0
(-450 3560);
DISPLAY 0.617021 (-450 3560);
PAINT ORANGE (-450 3560);
WIRE 17 -1 (150 2975)(150 3025);
WIRE 17 -1 (150 3025)(150 3050);
WIRE 17 -1 (150 3050)(-500 3050);
FORCEPROP 2 LAST SIG_NAME M_D_CKE<3:0>
J 0
(-475 3060);
DISPLAY 0.617021 (-475 3060);
PAINT ORANGE (-475 3060);
WIRE 17 -1 (150 2875)(150 2900);
WIRE 17 -1 (150 2825)(150 2875);
WIRE 17 -1 (150 2900)(-500 2900);
FORCEPROP 2 LAST SIG_NAME M_D_ODT<3:0>
J 0
(-475 2910);
DISPLAY 0.617021 (-475 2910);
PAINT ORANGE (-475 2910);
WIRE 17 -1 (150 2675)(150 2725);
WIRE 17 -1 (150 2625)(150 2675);
WIRE 17 -1 (150 2725)(150 2750);
WIRE 17 -1 (150 2750)(-500 2750);
FORCEPROP 2 LAST SIG_NAME M_D_ECC<7:0>
J 0
(-475 2760);
DISPLAY 0.617021 (-475 2760);
PAINT ORANGE (-475 2760);
WIRE 17 -1 (150 2575)(150 2625);
WIRE 17 -1 (150 2525)(150 2575);
WIRE 17 -1 (150 2475)(150 2525);
WIRE 17 -1 (150 2375)(150 2425);
WIRE 17 -1 (150 2425)(150 2475);
WIRE 16 -1 (5950 3150)(5950 3200);
WIRE 16 -1 (5950 3100)(5950 3150);
WIRE 16 -1 (5950 3150)(5750 3150);
WIRE 16 -1 (5950 3200)(5750 3200);
WIRE 16 -1 (5750 3100)(5950 3100);
WIRE 16 -1 (5950 3050)(5950 3100);
WIRE 16 -1 (5950 3000)(5950 3050);
WIRE 16 -1 (5950 3050)(5750 3050);
WIRE 16 -1 (5750 3000)(5950 3000);
WIRE 16 -1 (5950 2950)(5950 3000);
WIRE 16 -1 (5950 2900)(5950 2950);
WIRE 16 -1 (5950 2950)(5750 2950);
WIRE 16 -1 (5750 2900)(5950 2900);
WIRE 16 -1 (5950 2850)(5950 2900);
WIRE 16 -1 (5950 2800)(5950 2850);
WIRE 16 -1 (5950 2850)(5750 2850);
WIRE 16 -1 (5750 2800)(5950 2800);
WIRE 16 -1 (5950 2750)(5950 2800);
WIRE 16 -1 (5950 2700)(5950 2750);
WIRE 16 -1 (5950 2750)(5750 2750);
WIRE 16 -1 (5750 2700)(5950 2700);
WIRE 16 -1 (5950 2650)(5950 2700);
WIRE 16 -1 (5950 2600)(5950 2650);
WIRE 16 -1 (5950 2650)(5750 2650);
WIRE 16 -1 (5750 2600)(5950 2600);
WIRE 16 -1 (5950 2550)(5950 2600);
WIRE 16 -1 (5950 2500)(5950 2550);
WIRE 16 -1 (5950 2550)(5750 2550);
WIRE 16 -1 (5750 2500)(5950 2500);
WIRE 16 -1 (5950 2450)(5950 2500);
WIRE 16 -1 (5950 2400)(5950 2450);
WIRE 16 -1 (5950 2450)(5750 2450);
WIRE 16 -1 (5750 2400)(5950 2400);
WIRE 16 -1 (5950 2350)(5950 2400);
WIRE 16 -1 (5950 2300)(5950 2350);
WIRE 16 -1 (5950 2350)(5750 2350);
WIRE 16 -1 (5750 2300)(5950 2300);
WIRE 16 -1 (5950 2250)(5950 2300);
WIRE 16 -1 (5950 2200)(5950 2250);
WIRE 16 -1 (5950 2250)(5750 2250);
WIRE 16 -1 (5750 2200)(5950 2200);
WIRE 16 -1 (5950 2150)(5950 2200);
WIRE 16 -1 (5950 2100)(5950 2150);
WIRE 16 -1 (5950 2150)(5750 2150);
WIRE 16 -1 (5750 2100)(5950 2100);
WIRE 16 -1 (5950 2050)(5950 2100);
WIRE 16 -1 (5950 2050)(5750 2050);
WIRE 16 -1 (5950 2000)(5950 2050);
WIRE 16 -1 (5750 2000)(5950 2000);
WIRE 16 -1 (5950 1950)(5950 2000);
WIRE 16 -1 (5950 1900)(5950 1950);
WIRE 16 -1 (5950 1950)(5750 1950);
WIRE 16 -1 (5750 1900)(5950 1900);
WIRE 16 -1 (5950 1850)(5950 1900);
WIRE 16 -1 (5950 1800)(5950 1850);
WIRE 16 -1 (5950 1850)(5750 1850);
WIRE 16 -1 (5950 1750)(5950 1800);
WIRE 16 -1 (5950 1800)(5750 1800);
WIRE 16 -1 (5750 1750)(5950 1750);
WIRE 16 -1 (5950 1700)(5950 1750);
WIRE 16 -1 (5950 1650)(5950 1700);
WIRE 16 -1 (5950 1700)(5750 1700);
WIRE 16 -1 (5750 1650)(5950 1650);
WIRE 16 -1 (5950 1600)(5950 1650);
WIRE 16 -1 (5950 1550)(5950 1600);
WIRE 16 -1 (5950 1600)(5750 1600);
WIRE 16 -1 (5750 1550)(5950 1550);
WIRE 16 -1 (5950 1500)(5950 1550);
WIRE 16 -1 (5950 1450)(5950 1500);
WIRE 16 -1 (5950 1500)(5750 1500);
WIRE 16 -1 (5750 1450)(5950 1450);
WIRE 16 -1 (5950 1400)(5950 1450);
WIRE 16 -1 (5750 1400)(5950 1400);
WIRE 16 -1 (5950 1350)(5950 1400);
WIRE 16 -1 (5950 1300)(5950 1350);
WIRE 16 -1 (5950 1350)(5750 1350);
WIRE 16 -1 (5950 1250)(5950 1300);
WIRE 16 -1 (5950 1300)(5750 1300);
WIRE 16 -1 (5950 1200)(5950 1250);
WIRE 16 -1 (5950 1250)(5750 1250);
WIRE 16 -1 (5750 1200)(5950 1200);
WIRE 16 -1 (5950 1150)(5950 1200);
WIRE 16 -1 (5950 1100)(5950 1150);
WIRE 16 -1 (5950 1150)(5750 1150);
WIRE 16 -1 (5750 1100)(5950 1100);
WIRE 16 -1 (5950 1050)(5950 1100);
WIRE 16 -1 (5950 1050)(5750 1050);
WIRE 16 -1 (5950 1000)(5950 1050);
WIRE 16 -1 (5950 950)(5950 1000);
WIRE 16 -1 (5950 1000)(5750 1000);
WIRE 16 -1 (5750 950)(5950 950);
WIRE 16 -1 (5950 900)(5950 950);
WIRE 16 -1 (5950 900)(5950 800);
WIRE 16 -1 (5950 900)(5750 900);
WIRE 16 -1 (150 1800)(450 1800);
WIRE 16 -1 (150 1800)(150 1950);
WIRE 16 -1 (150 1950)(450 1950);
WIRE 16 -1 (-1650 1950)(150 1950);
WIRE 16 -1 (-1650 2050)(-1650 1950);
WIRE 16 -1 (-1200 1300)(-1200 1200);
WIRE 16 -1 (250 1850)(450 1850);
WIRE 16 -1 (250 1850)(250 1900);
WIRE 16 -1 (250 1900)(450 1900);
WIRE 16 -1 (250 1900)(-1350 1900);
WIRE 16 -1 (-1350 1900)(-1350 1825);
WIRE 16 -1 (3900 2350)(4100 2350);
WIRE 16 -1 (4100 2350)(4100 2400);
WIRE 16 -1 (3900 2400)(4100 2400);
WIRE 16 -1 (4100 2400)(4100 2575);
WIRE 16 -1 (4550 3200)(4750 3200);
WIRE 16 -1 (4550 3150)(4550 3200);
WIRE 16 -1 (4550 3150)(4750 3150);
WIRE 16 -1 (4550 3100)(4550 3150);
WIRE 16 -1 (4750 3100)(4550 3100);
WIRE 16 -1 (4550 3050)(4550 3100);
WIRE 16 -1 (4550 3050)(4750 3050);
WIRE 16 -1 (4550 3000)(4550 3050);
WIRE 16 -1 (4750 3000)(4550 3000);
WIRE 16 -1 (4550 2950)(4550 3000);
WIRE 16 -1 (4550 2950)(4750 2950);
WIRE 16 -1 (4550 2900)(4550 2950);
WIRE 16 -1 (4750 2900)(4550 2900);
WIRE 16 -1 (4550 2850)(4550 2900);
WIRE 16 -1 (4550 2850)(4750 2850);
WIRE 16 -1 (4550 2800)(4550 2850);
WIRE 16 -1 (4750 2800)(4550 2800);
WIRE 16 -1 (4550 2750)(4550 2800);
WIRE 16 -1 (4550 2750)(4750 2750);
WIRE 16 -1 (4550 2700)(4550 2750);
WIRE 16 -1 (4750 2700)(4550 2700);
WIRE 16 -1 (4550 2650)(4550 2700);
WIRE 16 -1 (4550 2650)(4750 2650);
WIRE 16 -1 (4550 2600)(4550 2650);
WIRE 16 -1 (4750 2600)(4550 2600);
WIRE 16 -1 (4550 2550)(4550 2600);
WIRE 16 -1 (4550 2550)(4750 2550);
WIRE 16 -1 (4550 2500)(4550 2550);
WIRE 16 -1 (4750 2500)(4550 2500);
WIRE 16 -1 (4550 2450)(4550 2500);
WIRE 16 -1 (4550 2450)(4750 2450);
WIRE 16 -1 (4550 2400)(4550 2450);
WIRE 16 -1 (4750 2400)(4550 2400);
WIRE 16 -1 (4550 2350)(4550 2400);
WIRE 16 -1 (4550 2350)(4750 2350);
WIRE 16 -1 (4550 2300)(4550 2350);
WIRE 16 -1 (4750 2300)(4550 2300);
WIRE 16 -1 (4550 2250)(4550 2300);
WIRE 16 -1 (4550 2250)(4750 2250);
WIRE 16 -1 (4550 2200)(4550 2250);
WIRE 16 -1 (4750 2200)(4550 2200);
WIRE 16 -1 (4550 2150)(4550 2200);
WIRE 16 -1 (4550 2150)(4750 2150);
WIRE 16 -1 (4550 2100)(4550 2150);
WIRE 16 -1 (4750 2100)(4550 2100);
WIRE 16 -1 (4550 2050)(4550 2100);
WIRE 16 -1 (4550 2050)(4750 2050);
WIRE 16 -1 (4550 2000)(4550 2050);
WIRE 16 -1 (4750 2000)(4550 2000);
WIRE 16 -1 (4550 1950)(4550 2000);
WIRE 16 -1 (4550 1950)(4750 1950);
WIRE 16 -1 (4550 1900)(4550 1950);
WIRE 16 -1 (4750 1900)(4550 1900);
WIRE 16 -1 (4550 1850)(4550 1900);
WIRE 16 -1 (4550 1850)(4750 1850);
WIRE 16 -1 (4550 1800)(4550 1850);
WIRE 16 -1 (4550 1800)(4750 1800);
WIRE 16 -1 (4550 1750)(4550 1800);
WIRE 16 -1 (4750 1750)(4550 1750);
WIRE 16 -1 (4550 1700)(4550 1750);
WIRE 16 -1 (4550 1700)(4750 1700);
WIRE 16 -1 (4550 1650)(4550 1700);
WIRE 16 -1 (4750 1650)(4550 1650);
WIRE 16 -1 (4550 1600)(4550 1650);
WIRE 16 -1 (4550 1600)(4750 1600);
WIRE 16 -1 (4550 1550)(4550 1600);
WIRE 16 -1 (4750 1550)(4550 1550);
WIRE 16 -1 (4550 1500)(4550 1550);
WIRE 16 -1 (4550 1500)(4750 1500);
WIRE 16 -1 (4550 1450)(4550 1500);
WIRE 16 -1 (4750 1450)(4550 1450);
WIRE 16 -1 (4550 1400)(4550 1450);
WIRE 16 -1 (4750 1400)(4550 1400);
WIRE 16 -1 (4550 1350)(4550 1400);
WIRE 16 -1 (4550 1350)(4750 1350);
WIRE 16 -1 (4550 1300)(4550 1350);
WIRE 16 -1 (4550 1300)(4750 1300);
WIRE 16 -1 (4550 1250)(4550 1300);
WIRE 16 -1 (4550 1250)(4750 1250);
WIRE 16 -1 (4550 1200)(4550 1250);
WIRE 16 -1 (4750 1200)(4550 1200);
WIRE 16 -1 (4550 1150)(4550 1200);
WIRE 16 -1 (4550 1150)(4750 1150);
WIRE 16 -1 (4550 1100)(4550 1150);
WIRE 16 -1 (4750 1100)(4550 1100);
WIRE 16 -1 (4550 1050)(4550 1100);
WIRE 16 -1 (4550 1050)(4750 1050);
WIRE 16 -1 (4550 1000)(4550 1050);
WIRE 16 -1 (4550 1000)(4750 1000);
WIRE 16 -1 (4550 950)(4550 1000);
WIRE 16 -1 (4750 950)(4550 950);
WIRE 16 -1 (4550 900)(4550 950);
WIRE 16 -1 (4550 900)(4750 900);
WIRE 16 -1 (4550 900)(4550 800);
WIRE 16 -1 (2700 2200)(2900 2200);
WIRE 16 -1 (2700 2250)(2700 2200);
WIRE 16 -1 (2700 2250)(2900 2250);
WIRE 16 -1 (2700 2300)(2700 2250);
WIRE 16 -1 (2900 2300)(2700 2300);
WIRE 16 -1 (2700 2350)(2700 2300);
WIRE 16 -1 (2700 2350)(2900 2350);
WIRE 16 -1 (2700 2400)(2700 2350);
WIRE 16 -1 (2700 2400)(2900 2400);
WIRE 16 -1 (2700 2500)(2700 2400);
WIRE 16 -1 (2700 2050)(2900 2050);
WIRE 16 -1 (2700 2050)(2700 2100);
WIRE 16 -1 (2700 2100)(2900 2100);
WIRE 16 -1 (2550 2100)(2700 2100);
WIRE 16 -1 (2550 2200)(2550 2100);
WIRE 16 -1 (2700 700)(2900 700);
WIRE 16 -1 (2700 700)(2700 750);
WIRE 16 -1 (2700 750)(2900 750);
WIRE 16 -1 (2700 750)(2700 800);
WIRE 16 -1 (2700 800)(2900 800);
WIRE 16 -1 (2700 800)(2700 850);
WIRE 16 -1 (2700 850)(2900 850);
WIRE 16 -1 (2700 850)(2700 900);
WIRE 16 -1 (2700 900)(2900 900);
WIRE 16 -1 (2700 900)(2700 950);
WIRE 16 -1 (2700 950)(2900 950);
WIRE 16 -1 (2700 950)(2700 1000);
WIRE 16 -1 (2700 1000)(2700 1050);
WIRE 16 -1 (2700 1000)(2900 1000);
WIRE 16 -1 (2700 1050)(2900 1050);
WIRE 16 -1 (2700 1050)(2700 1100);
WIRE 16 -1 (2700 1100)(2900 1100);
WIRE 16 -1 (2700 1100)(2700 1150);
WIRE 16 -1 (2700 1150)(2900 1150);
WIRE 16 -1 (2700 1150)(2700 1200);
WIRE 16 -1 (2700 1200)(2900 1200);
WIRE 16 -1 (2700 1200)(2700 1250);
WIRE 16 -1 (2700 1250)(2900 1250);
WIRE 16 -1 (2700 1250)(2700 1300);
WIRE 16 -1 (2700 1300)(2900 1300);
WIRE 16 -1 (2700 1300)(2700 1350);
WIRE 16 -1 (2700 1350)(2900 1350);
WIRE 16 -1 (2700 1350)(2700 1400);
WIRE 16 -1 (2700 1400)(2900 1400);
WIRE 16 -1 (2700 1400)(2700 1450);
WIRE 16 -1 (2700 1450)(2900 1450);
WIRE 16 -1 (2700 1450)(2700 1500);
WIRE 16 -1 (2700 1500)(2700 1550);
WIRE 16 -1 (2700 1500)(2900 1500);
WIRE 16 -1 (2700 1550)(2900 1550);
WIRE 16 -1 (2700 1550)(2700 1600);
WIRE 16 -1 (2700 1600)(2900 1600);
WIRE 16 -1 (2700 1600)(2700 1650);
WIRE 16 -1 (2700 1650)(2900 1650);
WIRE 16 -1 (2700 1650)(2700 1700);
WIRE 16 -1 (2700 1700)(2900 1700);
WIRE 16 -1 (2700 1700)(2700 1750);
WIRE 16 -1 (2700 1750)(2900 1750);
WIRE 16 -1 (2700 1750)(2700 1800);
WIRE 16 -1 (2700 1800)(2900 1800);
WIRE 16 -1 (2700 1800)(2700 1850);
WIRE 16 -1 (2700 1850)(2900 1850);
WIRE 16 -1 (2700 1850)(2700 1900);
WIRE 16 -1 (2700 1900)(2900 1900);
WIRE 16 -1 (2700 1900)(2700 1950);
WIRE 16 -1 (2700 1950)(2900 1950);
WIRE 16 -1 (2300 1950)(2700 1950);
WIRE 16 -1 (2300 2050)(2300 1950);
WIRE 16 -1 (-1300 1600)(-1200 1600);
WIRE 16 -1 (450 1600)(-1200 1600);
FORCEPROP 2 LAST SIG_NAME M_D_VREF
J 0
(-300 1610);
DISPLAY 0.617021 (-300 1610);
PAINT ORANGE (-300 1610);
WIRE 16 -1 (-1200 1500)(-1200 1600);
WIRE 16 -1 (0 2450)(-725 2450);
FORCEPROP 2 LAST SIG_NAME FM_DIMM_EVENT_COD_N
J 0
(-752 2465);
DISPLAY 0.617021 (-752 2465);
PAINT ORANGE (-752 2465);
WIRE 16 -1 (0 2150)(0 2450);
WIRE 16 -1 (0 2150)(450 2150);
WIRE 16 -1 (-400 1500)(450 1500);
FORCEPROP 2 LAST SIG_NAME TP_CH_D_DIMM_D1_RFU_2
J 0
(-350 1510);
DISPLAY 0.617021 (-350 1510);
PAINT ORANGE (-350 1510);
FORCEPROP 2 LASTPROP $XRERR UNIQUE?
J 0
(-640 1500);
DISPLAY 0.638298 (-640 1500);
PAINT MONO (-640 1500);
DISPLAY INVISIBLE (-640 1500);
WIRE 16 -1 (-400 1400)(450 1400);
FORCEPROP 2 LAST SIG_NAME TP_CH_D_DIMM_D1_RFU_0
J 0
(-350 1410);
DISPLAY 0.617021 (-350 1410);
PAINT ORANGE (-350 1410);
FORCEPROP 2 LASTPROP $XRERR UNIQUE?
J 0
(-640 1400);
DISPLAY 0.638298 (-640 1400);
PAINT MONO (-640 1400);
DISPLAY INVISIBLE (-640 1400);
WIRE 16 -1 (-400 1450)(450 1450);
FORCEPROP 2 LAST SIG_NAME TP_CH_D_DIMM_D1_RFU_1
J 0
(-350 1460);
DISPLAY 0.617021 (-350 1460);
PAINT ORANGE (-350 1460);
FORCEPROP 2 LASTPROP $XRERR UNIQUE?
J 0
(-640 1450);
DISPLAY 0.638298 (-640 1450);
PAINT MONO (-640 1450);
DISPLAY INVISIBLE (-640 1450);
WIRE 16 -1 (450 2100)(-525 2100);
FORCEPROP 2 LAST SIG_NAME M_D_ALERT_N
J 0
(-475 2110);
DISPLAY 0.617021 (-475 2110);
PAINT ORANGE (-475 2110);
WIRE 16 -1 (450 2050)(-500 2050);
FORCEPROP 2 LAST SIG_NAME M_D_ACT_N
J 0
(-450 2060);
DISPLAY 0.617021 (-450 2060);
PAINT ORANGE (-450 2060);
WIRE 16 -1 (450 1750)(-350 1750);
WIRE 16 -1 (-350 1700)(450 1700);
FORCEPROP 2 LAST SIG_NAME SMB_DDR_DEF_VPP_SCL
J 0
(-310 1710);
DISPLAY 0.617021 (-310 1710);
PAINT ORANGE (-310 1710);
WIRE 16 -1 (-400 1300)(450 1300);
FORCEPROP 2 LAST SIG_NAME FM_ADR_COMPLETE_DEF_N
J 0
(-350 1310);
DISPLAY 0.617021 (-350 1310);
PAINT ORANGE (-350 1310);
WIRE 16 -1 (1650 2000)(1450 2000);
WIRE 16 -1 (1650 1950)(1450 1950);
WIRE 16 -1 (1650 1900)(1450 1900);
WIRE 16 -1 (1650 1650)(1450 1650);
WIRE 16 -1 (1650 1600)(1450 1600);
WIRE 16 -1 (1650 1700)(1450 1700);
WIRE 16 -1 (1650 1750)(1450 1750);
WIRE 16 -1 (1650 1800)(1450 1800);
WIRE 16 -1 (1650 1850)(1450 1850);
WIRE 16 -1 (450 2550)(250 2550);
WIRE 16 -1 (450 2500)(250 2500);
WIRE 16 -1 (450 2450)(250 2450);
WIRE 16 -1 (450 2400)(250 2400);
WIRE 16 -1 (450 2350)(250 2350);
WIRE 16 -1 (100 2250)(100 2700);
WIRE 16 -1 (450 2250)(100 2250);
WIRE 16 -1 (100 2700)(-500 2700);
FORCEPROP 2 LAST SIG_NAME M_D_PAR
J 0
(-475 2710);
DISPLAY 0.617021 (-475 2710);
PAINT ORANGE (-475 2710);
WIRE 16 -1 (50 2200)(50 2650);
WIRE 16 -1 (450 2200)(50 2200);
WIRE 16 -1 (50 2650)(-500 2650);
FORCEPROP 2 LAST SIG_NAME M_DEF_RST_N
J 0
(-475 2660);
DISPLAY 0.617021 (-475 2660);
PAINT ORANGE (-475 2660);
WIRE 16 -1 (450 2650)(250 2650);
WIRE 16 -1 (450 2600)(250 2600);
WIRE 16 -1 (450 3000)(250 3000);
WIRE 16 -1 (450 2700)(250 2700);
WIRE 16 -1 (450 2800)(250 2800);
WIRE 16 -1 (450 2850)(250 2850);
WIRE 16 -1 (450 2950)(250 2950);
WIRE 16 -1 (450 3500)(50 3500);
WIRE 16 -1 (450 3450)(250 3450);
WIRE 16 -1 (450 3250)(250 3250);
WIRE 16 -1 (450 3200)(250 3200);
WIRE 16 -1 (450 3150)(250 3150);
WIRE 16 -1 (450 3400)(50 3400);
WIRE 16 -1 (450 3550)(250 3550);
WIRE 16 -1 (450 3100)(250 3100);
WIRE 16 -1 (300 3350)(300 3300);
WIRE 16 -1 (300 3350)(-500 3350);
FORCEPROP 2 LAST SIG_NAME M_D_C<2>
J 0
(-475 3360);
DISPLAY 0.617021 (-475 3360);
PAINT ORANGE (-475 3360);
WIRE 16 -1 (300 3300)(450 3300);
WIRE 16 -1 (450 3800)(250 3800);
WIRE 16 -1 (450 3900)(250 3900);
WIRE 16 -1 (450 3950)(250 3950);
WIRE 16 -1 (450 4050)(250 4050);
WIRE 16 -1 (450 3650)(250 3650);
WIRE 16 -1 (450 3700)(250 3700);
WIRE 16 -1 (450 3750)(250 3750);
WIRE 16 -1 (450 4000)(250 4000);
WIRE 16 -1 (1650 3050)(1450 3050);
WIRE 16 -1 (1650 3000)(1450 3000);
WIRE 16 -1 (1650 2850)(1450 2850);
WIRE 16 -1 (1650 2800)(1450 2800);
WIRE 16 -1 (1650 2750)(1450 2750);
WIRE 16 -1 (1650 2700)(1450 2700);
WIRE 16 -1 (1650 2650)(1450 2650);
WIRE 16 -1 (1650 2600)(1450 2600);
WIRE 16 -1 (1650 2550)(1450 2550);
WIRE 16 -1 (1650 2500)(1450 2500);
WIRE 16 -1 (1650 2400)(1450 2400);
WIRE 16 -1 (1650 2300)(1450 2300);
WIRE 16 -1 (1650 2250)(1450 2250);
WIRE 16 -1 (1650 2200)(1450 2200);
WIRE 16 -1 (1650 2150)(1450 2150);
WIRE 16 -1 (1650 2100)(1450 2100);
WIRE 16 -1 (1650 2050)(1450 2050);
WIRE 16 -1 (1650 2950)(1450 2950);
WIRE 16 -1 (1650 2900)(1450 2900);
WIRE 16 -1 (1650 2350)(1450 2350);
WIRE 16 -1 (1650 2450)(1450 2450);
WIRE 16 -1 (1650 3900)(1450 3900);
WIRE 16 -1 (1650 3850)(1450 3850);
WIRE 16 -1 (1650 3800)(1450 3800);
WIRE 16 -1 (1650 3750)(1450 3750);
WIRE 16 -1 (1650 3700)(1450 3700);
WIRE 16 -1 (1650 3650)(1450 3650);
WIRE 16 -1 (1650 3600)(1450 3600);
WIRE 16 -1 (1650 3550)(1450 3550);
WIRE 16 -1 (1650 3450)(1450 3450);
WIRE 16 -1 (1650 3300)(1450 3300);
WIRE 16 -1 (1650 3250)(1450 3250);
WIRE 16 -1 (1650 3200)(1450 3200);
WIRE 16 -1 (1650 3150)(1450 3150);
WIRE 16 -1 (1650 3100)(1450 3100);
WIRE 16 -1 (1650 3350)(1450 3350);
WIRE 16 -1 (1650 3400)(1450 3400);
WIRE 16 -1 (1650 3500)(1450 3500);
WIRE 16 -1 (1650 4050)(1450 4050);
WIRE 16 -1 (1650 4000)(1450 4000);
WIRE 16 -1 (1650 3950)(1450 3950);
WIRE 16 -1 (3850 3100)(4050 3100);
WIRE 16 -1 (3850 3200)(4050 3200);
WIRE 16 -1 (4050 3300)(3850 3300);
WIRE 16 -1 (4050 3400)(3850 3400);
WIRE 16 -1 (4050 3500)(3850 3500);
WIRE 16 -1 (4050 3600)(3850 3600);
WIRE 16 -1 (4050 3700)(3850 3700);
WIRE 16 -1 (4050 3800)(3850 3800);
WIRE 16 -1 (4050 3900)(3850 3900);
WIRE 16 -1 (4050 4000)(3850 4000);
WIRE 16 -1 (450 4500)(250 4500);
WIRE 16 -1 (450 4550)(250 4550);
WIRE 16 -1 (450 4100)(250 4100);
WIRE 16 -1 (450 4150)(250 4150);
WIRE 16 -1 (450 4200)(250 4200);
WIRE 16 -1 (450 4250)(250 4250);
WIRE 16 -1 (450 4300)(250 4300);
WIRE 16 -1 (450 4350)(250 4350);
WIRE 16 -1 (450 4400)(250 4400);
WIRE 16 -1 (450 4450)(250 4450);
WIRE 16 -1 (450 4600)(250 4600);
WIRE 16 -1 (450 4750)(250 4750);
WIRE 16 -1 (450 4650)(250 4650);
WIRE 16 -1 (450 4700)(250 4700);
WIRE 16 -1 (1650 4750)(1450 4750);
WIRE 16 -1 (1650 4700)(1450 4700);
WIRE 16 -1 (1650 4650)(1450 4650);
WIRE 16 -1 (1650 4600)(1450 4600);
WIRE 16 -1 (1650 4550)(1450 4550);
WIRE 16 -1 (1650 4400)(1450 4400);
WIRE 16 -1 (1650 4350)(1450 4350);
WIRE 16 -1 (1650 4450)(1450 4450);
WIRE 16 -1 (1650 4500)(1450 4500);
WIRE 16 -1 (1650 4300)(1450 4300);
WIRE 16 -1 (1650 4250)(1450 4250);
WIRE 16 -1 (1650 4200)(1450 4200);
WIRE 16 -1 (1650 4150)(1450 4150);
WIRE 16 -1 (1650 4100)(1450 4100);
WIRE 16 -1 (4050 4100)(3850 4100);
WIRE 16 -1 (4050 4200)(3850 4200);
WIRE 16 -1 (4050 4300)(3850 4300);
WIRE 16 -1 (4050 4400)(3850 4400);
WIRE 16 -1 (4050 4500)(3850 4500);
WIRE 16 -1 (4050 4600)(3850 4600);
WIRE 16 -1 (4050 4700)(3850 4700);
WIRE 16 -1 (4050 4800)(3850 4800);
WIRE 16 -1 (3850 3050)(4300 3050);
WIRE 16 -1 (4300 4050)(3850 4050);
WIRE 16 -1 (4300 4150)(3850 4150);
WIRE 16 -1 (4300 4250)(3850 4250);
WIRE 16 -1 (4300 4350)(3850 4350);
WIRE 16 -1 (4300 4450)(3850 4450);
WIRE 16 -1 (4300 4550)(3850 4550);
WIRE 16 -1 (4300 4650)(3850 4650);
WIRE 16 -1 (4300 4750)(3850 4750);
WIRE 16 -1 (3850 3150)(4300 3150);
WIRE 16 -1 (4300 3250)(3850 3250);
WIRE 16 -1 (4300 3350)(3850 3350);
WIRE 16 -1 (4300 3450)(3850 3450);
WIRE 16 -1 (4300 3550)(3850 3550);
WIRE 16 -1 (4300 3650)(3850 3650);
WIRE 16 -1 (4300 3750)(3850 3750);
WIRE 16 -1 (4300 3850)(3850 3850);
WIRE 16 -1 (4300 3950)(3850 3950);
DOT 1 (4550 2550);
DOT 1 (250 1900);
DOT 1 (150 1950);
DOT 1 (5950 3150);
DOT 1 (5950 3100);
DOT 1 (5950 3050);
DOT 1 (5950 2950);
DOT 1 (5950 3000);
DOT 1 (5950 2900);
DOT 1 (5950 2850);
DOT 1 (5950 2800);
DOT 1 (5950 2750);
DOT 1 (5950 2700);
DOT 1 (5950 2650);
DOT 1 (5950 2600);
DOT 1 (5950 2550);
DOT 1 (5950 2450);
DOT 1 (5950 2500);
DOT 1 (5950 2400);
DOT 1 (5950 2350);
DOT 1 (5950 2300);
DOT 1 (5950 2200);
DOT 1 (5950 2250);
DOT 1 (5950 2150);
DOT 1 (5950 2100);
DOT 1 (5950 2050);
DOT 1 (5950 2000);
DOT 1 (5950 1950);
DOT 1 (5950 1900);
DOT 1 (5950 1850);
DOT 1 (5950 1800);
DOT 1 (5950 1750);
DOT 1 (5950 1700);
DOT 1 (5950 1650);
DOT 1 (5950 1550);
DOT 1 (5950 1600);
DOT 1 (5950 1500);
DOT 1 (5950 1450);
DOT 1 (5950 1400);
DOT 1 (5950 1300);
DOT 1 (5950 1350);
DOT 1 (5950 1250);
DOT 1 (5950 1200);
DOT 1 (5950 1150);
DOT 1 (5950 1100);
DOT 1 (5950 1050);
DOT 1 (5950 1000);
DOT 1 (5950 950);
DOT 1 (5950 900);
DOT 1 (4550 3150);
DOT 1 (4550 3100);
DOT 1 (4550 3050);
DOT 1 (4550 2950);
DOT 1 (4550 3000);
DOT 1 (4550 2900);
DOT 1 (4550 2850);
DOT 1 (4550 2800);
DOT 1 (4550 2700);
DOT 1 (4550 2750);
DOT 1 (4550 2650);
DOT 1 (4550 2600);
DOT 1 (4550 2500);
DOT 1 (4550 2450);
DOT 1 (4550 2400);
DOT 1 (4550 2350);
DOT 1 (4550 2300);
DOT 1 (4550 2200);
DOT 1 (4550 2250);
DOT 1 (4550 2150);
DOT 1 (4550 2100);
DOT 1 (4550 2050);
DOT 1 (4100 2400);
DOT 1 (4550 2000);
DOT 1 (4550 1950);
DOT 1 (4550 1900);
DOT 1 (4550 1850);
DOT 1 (4550 1800);
DOT 1 (4550 1750);
DOT 1 (4550 1700);
DOT 1 (4550 1650);
DOT 1 (4550 1550);
DOT 1 (4550 1600);
DOT 1 (4550 1500);
DOT 1 (4550 1450);
DOT 1 (4550 1400);
DOT 1 (4550 1300);
DOT 1 (4550 1350);
DOT 1 (4550 1250);
DOT 1 (4550 1200);
DOT 1 (4550 1150);
DOT 1 (4550 1100);
DOT 1 (4550 1050);
DOT 1 (4550 1000);
DOT 1 (4550 900);
DOT 1 (4550 950);
DOT 1 (2700 2350);
DOT 1 (2700 2300);
DOT 1 (2700 2250);
DOT 1 (2700 2100);
DOT 1 (2700 1950);
DOT 1 (2700 1800);
DOT 1 (2700 1850);
DOT 1 (2700 1750);
DOT 1 (2700 1700);
DOT 1 (2700 1650);
DOT 1 (2700 1550);
DOT 1 (2700 1600);
DOT 1 (2700 1500);
DOT 1 (2700 1450);
DOT 1 (2700 1400);
DOT 1 (2700 1300);
DOT 1 (2700 1250);
DOT 1 (2700 1200);
DOT 1 (2700 1150);
DOT 1 (2700 1100);
DOT 1 (2700 1050);
DOT 1 (2700 1000);
DOT 1 (2700 900);
DOT 1 (2700 950);
DOT 1 (2700 850);
DOT 1 (2700 800);
DOT 1 (2700 750);
DOT 1 (-1200 1600);
DOT 1 (2700 2400);
DOT 1 (2700 1350);
DOT 1 (2700 1900);
FORCENOTE
SMBUS ADDR: 0XA2
(-1820 816) 0;
DISPLAY LEFT (-1820 816);
DISPLAY 1.957447 (-1820 816);
PAINT PURPLE (-1820 816);
FORCENOTE
PLACE CAP NEAR DIMM CONNECTOR
(-1788 1052) 0;
DISPLAY LEFT (-1788 1052);
DISPLAY 1.595745 (-1788 1052);
PAINT PURPLE (-1788 1052);
QUIT
